FILE_TYPE = MACRO_DRAWING;
SET COLOR_WIRE YELLOW;
SET COLOR_PROP MONO;
SET COLOR_DOT WHITE;
SET COLOR_ARC YELLOW;
SET COLOR_BODY GREEN;
SET COLOR_NOTE MONO;
SET PROP_DISPLAY VALUE;
SET PAGE_NUMBER P55;
FORCEADD OFFPAGE..1
R 2
(12800 4100);
FORCEPROP 2 LAST $XR0 96 
J 0
(12986 4100);
DISPLAY 0.638298 (12986 4100);
PAINT MONO (12986 4100);
FORCEPROP 2 LAST CDS_LIB mstr_standard
J 2
(12800 4100);
PAINT MONO (12800 4100);
DISPLAY INVISIBLE (12800 4100);
FORCEPROP 2 LAST PATH I10
J 2
(12500 4150);
DISPLAY 1.021277 (12500 4150);
PAINT ORANGE (12500 4150);
DISPLAY INVISIBLE (12500 4150);
FORCEPROP 1 LAST COMMENT_BODY TRUE
J 2
(12675 4000);
DISPLAY 0.872340 (12675 4000);
PAINT GREEN (12675 4000);
DISPLAY INVISIBLE (12675 4000);
FORCEPROP 1 LAST OFFPAGE TRUE
J 2
(12475 3975);
DISPLAY 0.872340 (12475 3975);
PAINT GREEN (12475 3975);
DISPLAY INVISIBLE (12475 3975);
FORCEADD OFFPAGE..1
(7975 1000);
FORCEPROP 2 LAST $XR0 112 
J 0
(7723 1000);
DISPLAY 0.638298 (7723 1000);
PAINT MONO (7723 1000);
FORCEPROP 1 LAST OFFPAGE TRUE
J 0
(8300 875);
DISPLAY 1.170213 (8300 875);
PAINT GREEN (8300 875);
DISPLAY INVISIBLE (8300 875);
FORCEPROP 2 LAST PATH I100
J 0
(8025 1075);
DISPLAY 1.021277 (8025 1075);
PAINT ORANGE (8025 1075);
DISPLAY INVISIBLE (8025 1075);
FORCEPROP 2 LAST CDS_LIB mstr_standard
J 0
(7975 1000);
PAINT MONO (7975 1000);
DISPLAY INVISIBLE (7975 1000);
FORCEPROP 1 LAST COMMENT_BODY TRUE
J 0
(8100 900);
DISPLAY 1.170213 (8100 900);
PAINT GREEN (8100 900);
DISPLAY INVISIBLE (8100 900);
FORCEADD OFFPAGE..1
(7975 950);
FORCEPROP 2 LAST $XR3 112 
J 0
(7393 950);
DISPLAY 0.638298 (7393 950);
PAINT MONO (7393 950);
FORCEPROP 2 LAST $XR2 21 
J 0
(7513 950);
DISPLAY 0.638298 (7513 950);
PAINT MONO (7513 950);
FORCEPROP 2 LAST $XR1 254 
J 0
(7603 950);
DISPLAY 0.638298 (7603 950);
PAINT MONO (7603 950);
FORCEPROP 2 LAST $XR0 111 
J 0
(7723 950);
DISPLAY 0.638298 (7723 950);
PAINT MONO (7723 950);
FORCEPROP 1 LAST OFFPAGE TRUE
J 0
(8300 825);
DISPLAY 1.170213 (8300 825);
PAINT GREEN (8300 825);
DISPLAY INVISIBLE (8300 825);
FORCEPROP 2 LAST PATH I101
J 0
(8025 1025);
DISPLAY 1.021277 (8025 1025);
PAINT ORANGE (8025 1025);
DISPLAY INVISIBLE (8025 1025);
FORCEPROP 1 LAST COMMENT_BODY TRUE
J 0
(8100 850);
DISPLAY 1.170213 (8100 850);
PAINT GREEN (8100 850);
DISPLAY INVISIBLE (8100 850);
FORCEPROP 2 LAST CDS_LIB mstr_standard
J 0
(7975 950);
PAINT MONO (7975 950);
DISPLAY INVISIBLE (7975 950);
FORCEADD OFFPAGE..1
(7975 900);
FORCEPROP 2 LAST $XR1 21 
J 0
(7633 900);
DISPLAY 0.638298 (7633 900);
PAINT MONO (7633 900);
FORCEPROP 2 LAST $XR0 112 
J 0
(7723 900);
DISPLAY 0.638298 (7723 900);
PAINT MONO (7723 900);
FORCEPROP 1 LAST OFFPAGE TRUE
J 0
(8300 775);
DISPLAY 1.170213 (8300 775);
PAINT GREEN (8300 775);
DISPLAY INVISIBLE (8300 775);
FORCEPROP 1 LAST COMMENT_BODY TRUE
J 0
(8100 800);
DISPLAY 1.170213 (8100 800);
PAINT GREEN (8100 800);
DISPLAY INVISIBLE (8100 800);
FORCEPROP 2 LAST PATH I102
J 0
(8025 975);
DISPLAY 1.021277 (8025 975);
PAINT ORANGE (8025 975);
DISPLAY INVISIBLE (8025 975);
FORCEPROP 2 LAST CDS_LIB mstr_standard
J 0
(7975 900);
PAINT MONO (7975 900);
DISPLAY INVISIBLE (7975 900);
FORCEADD OFFPAGE..1
(7975 850);
FORCEPROP 2 LAST $XR1 21 
J 0
(7633 850);
DISPLAY 0.638298 (7633 850);
PAINT MONO (7633 850);
FORCEPROP 2 LAST $XR0 112 
J 0
(7723 850);
DISPLAY 0.638298 (7723 850);
PAINT MONO (7723 850);
FORCEPROP 1 LAST OFFPAGE TRUE
J 0
(8300 725);
DISPLAY 1.170213 (8300 725);
PAINT GREEN (8300 725);
DISPLAY INVISIBLE (8300 725);
FORCEPROP 2 LAST PATH I103
J 0
(8025 925);
DISPLAY 1.021277 (8025 925);
PAINT ORANGE (8025 925);
DISPLAY INVISIBLE (8025 925);
FORCEPROP 2 LAST CDS_LIB mstr_standard
J 0
(7975 850);
PAINT MONO (7975 850);
DISPLAY INVISIBLE (7975 850);
FORCEPROP 1 LAST COMMENT_BODY TRUE
J 0
(8100 750);
DISPLAY 1.170213 (8100 750);
PAINT GREEN (8100 750);
DISPLAY INVISIBLE (8100 750);
FORCEADD OFFPAGE..1
(7975 3800);
FORCEPROP 2 LAST $XR0 103 
J 0
(7723 3800);
DISPLAY 0.638298 (7723 3800);
PAINT MONO (7723 3800);
FORCEPROP 1 LAST OFFPAGE TRUE
J 0
(8300 3675);
DISPLAY 1.170213 (8300 3675);
PAINT GREEN (8300 3675);
DISPLAY INVISIBLE (8300 3675);
FORCEPROP 2 LAST PATH I108
J 0
(8025 3875);
DISPLAY 1.021277 (8025 3875);
PAINT ORANGE (8025 3875);
DISPLAY INVISIBLE (8025 3875);
FORCEPROP 2 LAST CDS_LIB mstr_standard
J 0
(7975 3800);
PAINT MONO (7975 3800);
DISPLAY INVISIBLE (7975 3800);
FORCEPROP 1 LAST COMMENT_BODY TRUE
J 0
(8100 3700);
DISPLAY 1.170213 (8100 3700);
PAINT GREEN (8100 3700);
DISPLAY INVISIBLE (8100 3700);
FORCEADD OFFPAGE..1
(7975 3850);
FORCEPROP 2 LAST $XR0 103 
J 0
(7723 3850);
DISPLAY 0.638298 (7723 3850);
PAINT MONO (7723 3850);
FORCEPROP 1 LAST OFFPAGE TRUE
J 0
(8300 3725);
DISPLAY 1.170213 (8300 3725);
PAINT GREEN (8300 3725);
DISPLAY INVISIBLE (8300 3725);
FORCEPROP 2 LAST PATH I109
J 0
(8025 3925);
DISPLAY 1.021277 (8025 3925);
PAINT ORANGE (8025 3925);
DISPLAY INVISIBLE (8025 3925);
FORCEPROP 2 LAST CDS_LIB mstr_standard
J 0
(7975 3850);
PAINT MONO (7975 3850);
DISPLAY INVISIBLE (7975 3850);
FORCEPROP 1 LAST COMMENT_BODY TRUE
J 0
(8100 3750);
DISPLAY 1.170213 (8100 3750);
PAINT GREEN (8100 3750);
DISPLAY INVISIBLE (8100 3750);
FORCEADD RES..2
R 2
(6575 2725);
FORCEPROP 1 LAST TOLERANCE 1%
J 2
(6530 2750);
DISPLAY 0.617021 (6530 2750);
PAINT SKYBLUE (6530 2750);
FORCEPROP 1 LAST MATERIAL CHIP
J 2
(6535 2650);
DISPLAY 0.617021 (6535 2650);
PAINT SKYBLUE (6535 2650);
FORCEPROP 1 LASTPIN (6575 2625) $PN 2
J 2
(6570 2635);
DISPLAY 0.617021 (6570 2635);
PAINT ORANGE (6570 2635);
FORCEPROP 1 LASTPIN (6575 2825) $PN 1
J 2
(6570 2787);
DISPLAY 0.617021 (6570 2787);
PAINT ORANGE (6570 2787);
FORCEPROP 1 LAST LOCATION R7P19
J 2
(6530 2850);
DISPLAY 0.617021 (6530 2850);
PAINT AQUA (6530 2850);
FORCEPROP 1 LAST VALUE 100.0
J 2
(6530 2800);
DISPLAY 0.617021 (6530 2800);
PAINT SKYBLUE (6530 2800);
FORCEPROP 1 LAST WATTAGE 1/16W
J 2
(6535 2700);
DISPLAY 0.617021 (6535 2700);
PAINT SKYBLUE (6535 2700);
FORCEPROP 1 LAST PART_NUMBER G21796-017
J 2
(6585 2600);
DISPLAY 0.617021 (6585 2600);
PAINT BLUE (6585 2600);
FORCEPROP 1 LAST PACK_TYPE 0402
J 2
(6535 2550);
DISPLAY 0.617021 (6535 2550);
PAINT SKYBLUE (6535 2550);
FORCEPROP 2 LAST SEC_TYPE 0402
J 0
(6525 2950);
DISPLAY 1.021277 (6525 2950);
PAINT ORANGE (6525 2950);
DISPLAY INVISIBLE (6525 2950);
FORCEPROP 2 LAST BOM_COST PROC_SOCKET
J 0
(6550 2950);
PAINT MONO (6550 2950);
DISPLAY INVISIBLE (6550 2950);
FORCEPROP 2 LAST SEC 1
J 0
(6525 2950);
DISPLAY 0.680851 (6525 2950);
PAINT MONO (6525 2950);
DISPLAY INVISIBLE (6525 2950);
FORCEPROP 2 LAST CDS_LOCATION R7P19
J 2
(6530 2850);
DISPLAY 0.617021 (6530 2850);
PAINT AQUA (6530 2850);
DISPLAY INVISIBLE (6530 2850);
FORCEPROP 1 LAST PATH I115
J 2
(6525 2900);
DISPLAY 0.978723 (6525 2900);
PAINT WHITE (6525 2900);
DISPLAY INVISIBLE (6525 2900);
FORCEPROP 2 LAST ROOM CPU1
J 0
(6550 2900);
PAINT MONO (6550 2900);
DISPLAY INVISIBLE (6550 2900);
FORCEPROP 2 LAST CDS_LIB mstr_discrete
J 0
(6575 2725);
PAINT ORANGE (6575 2725);
DISPLAY INVISIBLE (6575 2725);
FORCEADD RES..2
R 2
(7700 2525);
FORCEPROP 1 LAST PART_NUMBER G21796-365
J 2
(7710 2400);
DISPLAY 0.617021 (7710 2400);
PAINT BLUE (7710 2400);
FORCEPROP 1 LASTPIN (7700 2625) $PN 1
J 2
(7695 2587);
DISPLAY 0.617021 (7695 2587);
PAINT ORANGE (7695 2587);
FORCEPROP 1 LASTPIN (7700 2425) $PN 2
J 2
(7695 2435);
DISPLAY 0.617021 (7695 2435);
PAINT ORANGE (7695 2435);
FORCEPROP 1 LAST LOCATION R3D1
J 2
(7655 2650);
DISPLAY 0.617021 (7655 2650);
PAINT AQUA (7655 2650);
FORCEPROP 1 LAST VALUE 90.9
J 2
(7655 2600);
DISPLAY 0.617021 (7655 2600);
PAINT SKYBLUE (7655 2600);
FORCEPROP 1 LAST TOLERANCE 1%
J 2
(7655 2550);
DISPLAY 0.617021 (7655 2550);
PAINT SKYBLUE (7655 2550);
FORCEPROP 1 LAST PACK_TYPE 0402
J 2
(7660 2350);
DISPLAY 0.617021 (7660 2350);
PAINT SKYBLUE (7660 2350);
FORCEPROP 1 LAST WATTAGE 1/16W
J 2
(7660 2500);
DISPLAY 0.617021 (7660 2500);
PAINT SKYBLUE (7660 2500);
FORCEPROP 1 LAST MATERIAL CHIP
J 2
(7660 2450);
DISPLAY 0.617021 (7660 2450);
PAINT SKYBLUE (7660 2450);
FORCEPROP 2 LAST CDS_LIB mstr_discrete
J 0
(7700 2525);
PAINT ORANGE (7700 2525);
DISPLAY INVISIBLE (7700 2525);
FORCEPROP 2 LAST SEC_TYPE 0402
J 0
(7650 2750);
DISPLAY 1.021277 (7650 2750);
PAINT ORANGE (7650 2750);
DISPLAY INVISIBLE (7650 2750);
FORCEPROP 2 LAST BOM_COST PROC_SOCKET
J 0
(7675 2750);
PAINT MONO (7675 2750);
DISPLAY INVISIBLE (7675 2750);
FORCEPROP 2 LAST SEC 1
J 0
(7650 2750);
DISPLAY 0.680851 (7650 2750);
PAINT MONO (7650 2750);
DISPLAY INVISIBLE (7650 2750);
FORCEPROP 2 LAST CDS_LOCATION R3D1
J 2
(7655 2650);
DISPLAY 0.617021 (7655 2650);
PAINT AQUA (7655 2650);
DISPLAY INVISIBLE (7655 2650);
FORCEPROP 1 LAST PATH I116
J 2
(7650 2700);
DISPLAY 0.978723 (7650 2700);
PAINT WHITE (7650 2700);
DISPLAY INVISIBLE (7650 2700);
FORCEPROP 2 LAST ROOM CPU1
J 0
(7675 2700);
PAINT MONO (7675 2700);
DISPLAY INVISIBLE (7675 2700);
FORCEADD RES..2
R 2
(7475 2525);
FORCEPROP 1 LASTPIN (7475 2625) $PN 1
J 2
(7470 2587);
DISPLAY 0.617021 (7470 2587);
PAINT ORANGE (7470 2587);
FORCEPROP 1 LAST TOLERANCE 1%
J 2
(7430 2550);
DISPLAY 0.617021 (7430 2550);
PAINT SKYBLUE (7430 2550);
FORCEPROP 1 LASTPIN (7475 2425) $PN 2
J 2
(7470 2435);
DISPLAY 0.617021 (7470 2435);
PAINT ORANGE (7470 2435);
FORCEPROP 1 LAST PACK_TYPE 0402
J 2
(7435 2350);
DISPLAY 0.617021 (7435 2350);
PAINT SKYBLUE (7435 2350);
FORCEPROP 1 LAST MATERIAL CHIP
J 2
(7435 2450);
DISPLAY 0.617021 (7435 2450);
PAINT SKYBLUE (7435 2450);
FORCEPROP 1 LAST LOCATION R3D2
J 2
(7430 2650);
DISPLAY 0.617021 (7430 2650);
PAINT AQUA (7430 2650);
FORCEPROP 1 LAST VALUE 90.9
J 2
(7430 2600);
DISPLAY 0.617021 (7430 2600);
PAINT SKYBLUE (7430 2600);
FORCEPROP 1 LAST WATTAGE 1/16W
J 2
(7435 2500);
DISPLAY 0.617021 (7435 2500);
PAINT SKYBLUE (7435 2500);
FORCEPROP 1 LAST PART_NUMBER G21796-365
J 2
(7485 2400);
DISPLAY 0.617021 (7485 2400);
PAINT BLUE (7485 2400);
FORCEPROP 2 LAST ROOM CPU1
J 0
(7450 2700);
PAINT MONO (7450 2700);
DISPLAY INVISIBLE (7450 2700);
FORCEPROP 1 LAST PATH I117
J 2
(7425 2700);
DISPLAY 0.978723 (7425 2700);
PAINT WHITE (7425 2700);
DISPLAY INVISIBLE (7425 2700);
FORCEPROP 2 LAST CDS_LOCATION R3D2
J 2
(7430 2650);
DISPLAY 0.617021 (7430 2650);
PAINT AQUA (7430 2650);
DISPLAY INVISIBLE (7430 2650);
FORCEPROP 2 LAST SEC_TYPE 0402
J 0
(7425 2750);
DISPLAY 1.021277 (7425 2750);
PAINT ORANGE (7425 2750);
DISPLAY INVISIBLE (7425 2750);
FORCEPROP 2 LAST BOM_COST PROC_SOCKET
J 0
(7450 2750);
PAINT MONO (7450 2750);
DISPLAY INVISIBLE (7450 2750);
FORCEPROP 2 LAST SEC 1
J 0
(7425 2750);
DISPLAY 0.680851 (7425 2750);
PAINT MONO (7425 2750);
DISPLAY INVISIBLE (7425 2750);
FORCEPROP 2 LAST CDS_LIB mstr_discrete
J 0
(7475 2525);
PAINT ORANGE (7475 2525);
DISPLAY INVISIBLE (7475 2525);
FORCEADD RES..2
R 2
(7250 2525);
FORCEPROP 1 LASTPIN (7250 2625) $PN 1
J 2
(7245 2587);
DISPLAY 0.617021 (7245 2587);
PAINT ORANGE (7245 2587);
FORCEPROP 1 LASTPIN (7250 2425) $PN 2
J 2
(7245 2435);
DISPLAY 0.617021 (7245 2435);
PAINT ORANGE (7245 2435);
FORCEPROP 1 LAST PACK_TYPE 0402
J 2
(7210 2350);
DISPLAY 0.617021 (7210 2350);
PAINT SKYBLUE (7210 2350);
FORCEPROP 1 LAST TOLERANCE 1%
J 2
(7205 2550);
DISPLAY 0.617021 (7205 2550);
PAINT SKYBLUE (7205 2550);
FORCEPROP 1 LAST VALUE 100.0
J 2
(7205 2600);
DISPLAY 0.617021 (7205 2600);
PAINT SKYBLUE (7205 2600);
FORCEPROP 1 LAST LOCATION R3D3
J 2
(7205 2650);
DISPLAY 0.617021 (7205 2650);
PAINT AQUA (7205 2650);
FORCEPROP 1 LAST WATTAGE 1/16W
J 2
(7210 2500);
DISPLAY 0.617021 (7210 2500);
PAINT SKYBLUE (7210 2500);
FORCEPROP 1 LAST MATERIAL CHIP
J 2
(7210 2450);
DISPLAY 0.617021 (7210 2450);
PAINT SKYBLUE (7210 2450);
FORCEPROP 1 LAST PART_NUMBER G21796-017
J 2
(7260 2400);
DISPLAY 0.617021 (7260 2400);
PAINT BLUE (7260 2400);
FORCEPROP 2 LAST SEC_TYPE 0402
J 0
(7200 2750);
DISPLAY 1.021277 (7200 2750);
PAINT ORANGE (7200 2750);
DISPLAY INVISIBLE (7200 2750);
FORCEPROP 2 LAST BOM_COST PROC_SOCKET
J 0
(7225 2750);
PAINT MONO (7225 2750);
DISPLAY INVISIBLE (7225 2750);
FORCEPROP 2 LAST SEC 1
J 0
(7200 2750);
DISPLAY 0.680851 (7200 2750);
PAINT MONO (7200 2750);
DISPLAY INVISIBLE (7200 2750);
FORCEPROP 2 LAST CDS_LOCATION R3D3
J 2
(7205 2650);
DISPLAY 0.617021 (7205 2650);
PAINT AQUA (7205 2650);
DISPLAY INVISIBLE (7205 2650);
FORCEPROP 1 LAST PATH I118
J 2
(7200 2700);
DISPLAY 0.978723 (7200 2700);
PAINT WHITE (7200 2700);
DISPLAY INVISIBLE (7200 2700);
FORCEPROP 2 LAST ROOM CPU1
J 0
(7225 2700);
PAINT MONO (7225 2700);
DISPLAY INVISIBLE (7225 2700);
FORCEPROP 2 LAST CDS_LIB mstr_discrete
J 0
(7250 2525);
PAINT ORANGE (7250 2525);
DISPLAY INVISIBLE (7250 2525);
FORCEADD RES..2
R 2
(7025 2600);
FORCEPROP 1 LASTPIN (7025 2700) $PN 1
J 2
(7020 2662);
DISPLAY 0.617021 (7020 2662);
PAINT ORANGE (7020 2662);
FORCEPROP 1 LASTPIN (7025 2500) $PN 2
J 2
(7020 2510);
DISPLAY 0.617021 (7020 2510);
PAINT ORANGE (7020 2510);
FORCEPROP 1 LAST PACK_TYPE 0402
J 2
(6985 2425);
DISPLAY 0.617021 (6985 2425);
PAINT SKYBLUE (6985 2425);
FORCEPROP 1 LAST PART_NUMBER G21796-365
J 2
(7035 2475);
DISPLAY 0.617021 (7035 2475);
PAINT BLUE (7035 2475);
FORCEPROP 1 LAST MATERIAL CHIP
J 2
(6985 2525);
DISPLAY 0.617021 (6985 2525);
PAINT SKYBLUE (6985 2525);
FORCEPROP 1 LAST WATTAGE 1/16W
J 2
(6985 2575);
DISPLAY 0.617021 (6985 2575);
PAINT SKYBLUE (6985 2575);
FORCEPROP 1 LAST TOLERANCE 1%
J 2
(6980 2625);
DISPLAY 0.617021 (6980 2625);
PAINT SKYBLUE (6980 2625);
FORCEPROP 1 LAST VALUE 90.9
J 2
(6980 2675);
DISPLAY 0.617021 (6980 2675);
PAINT SKYBLUE (6980 2675);
FORCEPROP 1 LAST LOCATION R7P16
J 2
(6980 2725);
DISPLAY 0.617021 (6980 2725);
PAINT AQUA (6980 2725);
FORCEPROP 2 LAST SEC_TYPE 0402
J 0
(6975 2825);
DISPLAY 1.021277 (6975 2825);
PAINT ORANGE (6975 2825);
DISPLAY INVISIBLE (6975 2825);
FORCEPROP 2 LAST BOM_COST PROC_SOCKET
J 0
(7000 2825);
PAINT MONO (7000 2825);
DISPLAY INVISIBLE (7000 2825);
FORCEPROP 2 LAST SEC 1
J 0
(6975 2825);
DISPLAY 0.680851 (6975 2825);
PAINT MONO (6975 2825);
DISPLAY INVISIBLE (6975 2825);
FORCEPROP 2 LAST ROOM CPU1
J 0
(7000 2775);
PAINT MONO (7000 2775);
DISPLAY INVISIBLE (7000 2775);
FORCEPROP 2 LAST CDS_LOCATION R7P16
J 2
(6980 2725);
DISPLAY 0.617021 (6980 2725);
PAINT AQUA (6980 2725);
DISPLAY INVISIBLE (6980 2725);
FORCEPROP 1 LAST PATH I119
J 2
(6975 2775);
DISPLAY 0.978723 (6975 2775);
PAINT WHITE (6975 2775);
DISPLAY INVISIBLE (6975 2775);
FORCEPROP 2 LAST CDS_LIB mstr_discrete
J 0
(7025 2600);
PAINT ORANGE (7025 2600);
DISPLAY INVISIBLE (7025 2600);
FORCEADD GND..1
(6650 2250);
FORCEPROP 3 LASTPIN (6650 2300) SIG_NAME GND\g
J 0
(6660 2310);
DISPLAY 0.659574 (6660 2310);
PAINT MONO (6660 2310);
DISPLAY INVISIBLE (6660 2310);
FORCEPROP 1 LAST PATH I121
J 0
(6725 2250);
DISPLAY 0.872340 (6725 2250);
PAINT AQUA (6725 2250);
DISPLAY INVISIBLE (6725 2250);
FORCEPROP 1 LAST SIZE 1B
J 0
(6725 2200);
DISPLAY 1.170213 (6725 2200);
PAINT GREEN (6725 2200);
DISPLAY INVISIBLE (6725 2200);
FORCEPROP 1 LAST HDL_POWER GND
J 0
(6650 2400);
DISPLAY 1.170213 (6650 2400);
PAINT GREEN (6650 2400);
DISPLAY INVISIBLE (6650 2400);
FORCEPROP 1 LAST VOLTAGE 0.0V
J 0
(6605 2207);
DISPLAY 0.340426 (6605 2207);
PAINT SKYBLUE (6605 2207);
DISPLAY INVISIBLE (6605 2207);
FORCEPROP 2 LAST CDS_LIB mstr_symbols
J 0
(6650 2250);
PAINT ORANGE (6650 2250);
DISPLAY INVISIBLE (6650 2250);
FORCEPROP 1 LAST BODY_TYPE PLUMBING
J 0
(6605 2207);
DISPLAY 0.340426 (6605 2207);
PAINT GREEN (6605 2207);
DISPLAY INVISIBLE (6605 2207);
FORCEADD GND..1
(6600 1100);
FORCEPROP 3 LASTPIN (6600 1150) SIG_NAME GND\g
J 0
(6610 1160);
DISPLAY 0.659574 (6610 1160);
PAINT MONO (6610 1160);
DISPLAY INVISIBLE (6610 1160);
FORCEPROP 1 LAST SIZE 1B
J 0
(6675 1050);
DISPLAY 1.170213 (6675 1050);
PAINT GREEN (6675 1050);
DISPLAY INVISIBLE (6675 1050);
FORCEPROP 1 LAST PATH I122
J 0
(6675 1100);
DISPLAY 0.872340 (6675 1100);
PAINT AQUA (6675 1100);
DISPLAY INVISIBLE (6675 1100);
FORCEPROP 1 LAST HDL_POWER GND
J 0
(6600 1250);
DISPLAY 1.170213 (6600 1250);
PAINT GREEN (6600 1250);
DISPLAY INVISIBLE (6600 1250);
FORCEPROP 1 LAST BODY_TYPE PLUMBING
J 0
(6555 1057);
DISPLAY 0.340426 (6555 1057);
PAINT GREEN (6555 1057);
DISPLAY INVISIBLE (6555 1057);
FORCEPROP 2 LAST CDS_LIB mstr_symbols
J 0
(6600 1100);
PAINT ORANGE (6600 1100);
DISPLAY INVISIBLE (6600 1100);
FORCEPROP 1 LAST VOLTAGE 0.0V
J 0
(6555 1057);
DISPLAY 0.340426 (6555 1057);
PAINT SKYBLUE (6555 1057);
DISPLAY INVISIBLE (6555 1057);
FORCEADD RES..2
R 2
(6600 1425);
FORCEPROP 1 LAST LOCATION R7P8
J 2
(6555 1550);
DISPLAY 0.617021 (6555 1550);
PAINT AQUA (6555 1550);
FORCEPROP 1 LASTPIN (6600 1525) $PN 1
J 2
(6595 1487);
DISPLAY 0.617021 (6595 1487);
PAINT ORANGE (6595 1487);
FORCEPROP 1 LASTPIN (6600 1325) $PN 2
J 2
(6595 1335);
DISPLAY 0.617021 (6595 1335);
PAINT ORANGE (6595 1335);
FORCEPROP 1 LAST VALUE 49.9
J 2
(6555 1500);
DISPLAY 0.617021 (6555 1500);
PAINT SKYBLUE (6555 1500);
FORCEPROP 1 LAST TOLERANCE 1%
J 2
(6555 1450);
DISPLAY 0.617021 (6555 1450);
PAINT SKYBLUE (6555 1450);
FORCEPROP 1 LAST MATERIAL CHIP
J 2
(6560 1350);
DISPLAY 0.617021 (6560 1350);
PAINT SKYBLUE (6560 1350);
FORCEPROP 1 LAST PACK_TYPE 0402
J 2
(6560 1250);
DISPLAY 0.617021 (6560 1250);
PAINT SKYBLUE (6560 1250);
FORCEPROP 1 LAST PART_NUMBER G21796-047
J 2
(6610 1300);
DISPLAY 0.617021 (6610 1300);
PAINT BLUE (6610 1300);
FORCEPROP 1 LAST WATTAGE 1/16W
J 2
(6560 1400);
DISPLAY 0.617021 (6560 1400);
PAINT SKYBLUE (6560 1400);
FORCEPROP 2 LAST SEC_TYPE 0402
J 0
(6550 1650);
DISPLAY 1.021277 (6550 1650);
PAINT ORANGE (6550 1650);
DISPLAY INVISIBLE (6550 1650);
FORCEPROP 2 LAST BOM_COST PROC_SOCKET
J 0
(6575 1650);
PAINT MONO (6575 1650);
DISPLAY INVISIBLE (6575 1650);
FORCEPROP 2 LAST SEC 1
J 0
(6550 1650);
DISPLAY 0.680851 (6550 1650);
PAINT MONO (6550 1650);
DISPLAY INVISIBLE (6550 1650);
FORCEPROP 2 LAST CDS_LOCATION R7P8
J 2
(6555 1550);
DISPLAY 0.617021 (6555 1550);
PAINT AQUA (6555 1550);
DISPLAY INVISIBLE (6555 1550);
FORCEPROP 1 LAST PATH I123
J 2
(6550 1600);
DISPLAY 0.978723 (6550 1600);
PAINT WHITE (6550 1600);
DISPLAY INVISIBLE (6550 1600);
FORCEPROP 2 LAST ROOM CPU1
J 0
(6575 1600);
PAINT MONO (6575 1600);
DISPLAY INVISIBLE (6575 1600);
FORCEPROP 2 LAST CDS_LIB mstr_discrete
J 0
(6600 1425);
PAINT ORANGE (6600 1425);
DISPLAY INVISIBLE (6600 1425);
FORCEADD RES..2
R 2
(6825 1425);
FORCEPROP 1 LASTPIN (6825 1525) $PN 1
J 2
(6820 1487);
DISPLAY 0.617021 (6820 1487);
PAINT ORANGE (6820 1487);
FORCEPROP 1 LASTPIN (6825 1325) $PN 2
J 2
(6820 1335);
DISPLAY 0.617021 (6820 1335);
PAINT ORANGE (6820 1335);
FORCEPROP 1 LAST MATERIAL CHIP
J 2
(6785 1350);
DISPLAY 0.617021 (6785 1350);
PAINT SKYBLUE (6785 1350);
FORCEPROP 1 LAST VALUE 49.9
J 2
(6780 1500);
DISPLAY 0.617021 (6780 1500);
PAINT SKYBLUE (6780 1500);
FORCEPROP 1 LAST PACK_TYPE 0402
J 2
(6785 1250);
DISPLAY 0.617021 (6785 1250);
PAINT SKYBLUE (6785 1250);
FORCEPROP 1 LAST LOCATION R7P10
J 2
(6780 1550);
DISPLAY 0.617021 (6780 1550);
PAINT AQUA (6780 1550);
FORCEPROP 1 LAST PART_NUMBER G21796-047
J 2
(6835 1300);
DISPLAY 0.617021 (6835 1300);
PAINT BLUE (6835 1300);
FORCEPROP 1 LAST WATTAGE 1/16W
J 2
(6785 1400);
DISPLAY 0.617021 (6785 1400);
PAINT SKYBLUE (6785 1400);
FORCEPROP 1 LAST TOLERANCE 1%
J 2
(6780 1450);
DISPLAY 0.617021 (6780 1450);
PAINT SKYBLUE (6780 1450);
FORCEPROP 2 LAST SEC_TYPE 0402
J 0
(6775 1650);
DISPLAY 1.021277 (6775 1650);
PAINT ORANGE (6775 1650);
DISPLAY INVISIBLE (6775 1650);
FORCEPROP 2 LAST BOM_COST PROC_SOCKET
J 0
(6800 1650);
PAINT MONO (6800 1650);
DISPLAY INVISIBLE (6800 1650);
FORCEPROP 2 LAST SEC 1
J 0
(6775 1650);
DISPLAY 0.680851 (6775 1650);
PAINT MONO (6775 1650);
DISPLAY INVISIBLE (6775 1650);
FORCEPROP 2 LAST CDS_LOCATION R7P10
J 2
(6780 1550);
DISPLAY 0.617021 (6780 1550);
PAINT AQUA (6780 1550);
DISPLAY INVISIBLE (6780 1550);
FORCEPROP 1 LAST PATH I124
J 2
(6775 1600);
DISPLAY 0.978723 (6775 1600);
PAINT WHITE (6775 1600);
DISPLAY INVISIBLE (6775 1600);
FORCEPROP 2 LAST ROOM CPU1
J 0
(6800 1600);
PAINT MONO (6800 1600);
DISPLAY INVISIBLE (6800 1600);
FORCEPROP 2 LAST CDS_LIB mstr_discrete
J 0
(6825 1425);
PAINT ORANGE (6825 1425);
DISPLAY INVISIBLE (6825 1425);
FORCEADD RES..2
R 2
(7050 1425);
FORCEPROP 1 LAST LOCATION R3D19
J 2
(7005 1550);
DISPLAY 0.617021 (7005 1550);
PAINT AQUA (7005 1550);
FORCEPROP 1 LASTPIN (7050 1525) $PN 1
J 2
(7045 1487);
DISPLAY 0.617021 (7045 1487);
PAINT ORANGE (7045 1487);
FORCEPROP 1 LASTPIN (7050 1325) $PN 2
J 2
(7045 1335);
DISPLAY 0.617021 (7045 1335);
PAINT ORANGE (7045 1335);
FORCEPROP 1 LAST TOLERANCE 1%
J 2
(7005 1450);
DISPLAY 0.617021 (7005 1450);
PAINT SKYBLUE (7005 1450);
FORCEPROP 1 LAST PACK_TYPE 0402
J 2
(7010 1250);
DISPLAY 0.617021 (7010 1250);
PAINT SKYBLUE (7010 1250);
FORCEPROP 1 LAST MATERIAL CHIP
J 2
(7010 1350);
DISPLAY 0.617021 (7010 1350);
PAINT SKYBLUE (7010 1350);
FORCEPROP 1 LAST WATTAGE 1/16W
J 2
(7010 1400);
DISPLAY 0.617021 (7010 1400);
PAINT SKYBLUE (7010 1400);
FORCEPROP 1 LAST PART_NUMBER G21796-047
J 2
(7060 1300);
DISPLAY 0.617021 (7060 1300);
PAINT BLUE (7060 1300);
FORCEPROP 1 LAST VALUE 49.9
J 2
(7005 1500);
DISPLAY 0.617021 (7005 1500);
PAINT SKYBLUE (7005 1500);
FORCEPROP 2 LAST SEC_TYPE 0402
J 0
(7000 1650);
DISPLAY 1.021277 (7000 1650);
PAINT ORANGE (7000 1650);
DISPLAY INVISIBLE (7000 1650);
FORCEPROP 2 LAST BOM_COST PROC_SOCKET
J 0
(7025 1650);
PAINT MONO (7025 1650);
DISPLAY INVISIBLE (7025 1650);
FORCEPROP 2 LAST SEC 1
J 0
(7000 1650);
DISPLAY 0.680851 (7000 1650);
PAINT MONO (7000 1650);
DISPLAY INVISIBLE (7000 1650);
FORCEPROP 2 LAST CDS_LOCATION R3D19
J 2
(7005 1550);
DISPLAY 0.617021 (7005 1550);
PAINT AQUA (7005 1550);
DISPLAY INVISIBLE (7005 1550);
FORCEPROP 1 LAST PATH I125
J 2
(7000 1600);
DISPLAY 0.978723 (7000 1600);
PAINT WHITE (7000 1600);
DISPLAY INVISIBLE (7000 1600);
FORCEPROP 2 LAST ROOM CPU1
J 0
(7025 1600);
PAINT MONO (7025 1600);
DISPLAY INVISIBLE (7025 1600);
FORCEPROP 2 LAST CDS_LIB mstr_discrete
J 0
(7050 1425);
PAINT ORANGE (7050 1425);
DISPLAY INVISIBLE (7050 1425);
FORCEADD RES..2
R 2
(7275 1425);
FORCEPROP 1 LAST TOLERANCE 1%
J 2
(7230 1450);
DISPLAY 0.617021 (7230 1450);
PAINT SKYBLUE (7230 1450);
FORCEPROP 1 LASTPIN (7275 1525) $PN 1
J 2
(7270 1487);
DISPLAY 0.617021 (7270 1487);
PAINT ORANGE (7270 1487);
FORCEPROP 1 LASTPIN (7275 1325) $PN 2
J 2
(7270 1335);
DISPLAY 0.617021 (7270 1335);
PAINT ORANGE (7270 1335);
FORCEPROP 1 LAST LOCATION R7P11
J 2
(7230 1550);
DISPLAY 0.617021 (7230 1550);
PAINT AQUA (7230 1550);
FORCEPROP 1 LAST WATTAGE 1/16W
J 2
(7235 1400);
DISPLAY 0.617021 (7235 1400);
PAINT SKYBLUE (7235 1400);
FORCEPROP 1 LAST MATERIAL CHIP
J 2
(7235 1350);
DISPLAY 0.617021 (7235 1350);
PAINT SKYBLUE (7235 1350);
FORCEPROP 1 LAST PACK_TYPE 0402
J 2
(7235 1250);
DISPLAY 0.617021 (7235 1250);
PAINT SKYBLUE (7235 1250);
FORCEPROP 1 LAST PART_NUMBER G21796-047
J 2
(7285 1300);
DISPLAY 0.617021 (7285 1300);
PAINT BLUE (7285 1300);
FORCEPROP 1 LAST VALUE 49.9
J 2
(7230 1500);
DISPLAY 0.617021 (7230 1500);
PAINT SKYBLUE (7230 1500);
FORCEPROP 2 LAST SEC_TYPE 0402
J 0
(7225 1650);
DISPLAY 1.021277 (7225 1650);
PAINT ORANGE (7225 1650);
DISPLAY INVISIBLE (7225 1650);
FORCEPROP 2 LAST BOM_COST PROC_SOCKET
J 0
(7250 1650);
PAINT MONO (7250 1650);
DISPLAY INVISIBLE (7250 1650);
FORCEPROP 2 LAST SEC 1
J 0
(7225 1650);
DISPLAY 0.680851 (7225 1650);
PAINT MONO (7225 1650);
DISPLAY INVISIBLE (7225 1650);
FORCEPROP 2 LAST CDS_LOCATION R7P11
J 2
(7230 1550);
DISPLAY 0.617021 (7230 1550);
PAINT AQUA (7230 1550);
DISPLAY INVISIBLE (7230 1550);
FORCEPROP 1 LAST PATH I126
J 2
(7225 1600);
DISPLAY 0.978723 (7225 1600);
PAINT WHITE (7225 1600);
DISPLAY INVISIBLE (7225 1600);
FORCEPROP 2 LAST ROOM CPU1
J 0
(7250 1600);
PAINT MONO (7250 1600);
DISPLAY INVISIBLE (7250 1600);
FORCEPROP 2 LAST CDS_LIB mstr_discrete
J 0
(7275 1425);
PAINT ORANGE (7275 1425);
DISPLAY INVISIBLE (7275 1425);
FORCEADD OFFPAGE..3
(13725 3650);
FORCEPROP 2 LAST $XR2 226 
J 0
(14179 3650);
DISPLAY 0.638298 (14179 3650);
PAINT MONO (14179 3650);
FORCEPROP 2 LAST $XR1 223 
J 0
(14059 3650);
DISPLAY 0.638298 (14059 3650);
PAINT MONO (14059 3650);
FORCEPROP 2 LAST $XR0 193 
J 0
(13939 3650);
DISPLAY 0.638298 (13939 3650);
PAINT MONO (13939 3650);
FORCEPROP 2 LAST PATH I13
J 0
(13925 3725);
DISPLAY 1.021277 (13925 3725);
PAINT ORANGE (13925 3725);
DISPLAY INVISIBLE (13925 3725);
FORCEPROP 1 LAST OFFPAGE TRUE
J 0
(14050 3525);
DISPLAY 1.170213 (14050 3525);
PAINT GREEN (14050 3525);
DISPLAY INVISIBLE (14050 3525);
FORCEPROP 2 LAST CDS_LIB mstr_standard
J 0
(13725 3650);
PAINT MONO (13725 3650);
DISPLAY INVISIBLE (13725 3650);
FORCEPROP 1 LAST COMMENT_BODY TRUE
J 0
(13675 3550);
DISPLAY 1.170213 (13675 3550);
PAINT GREEN (13675 3550);
DISPLAY INVISIBLE (13675 3550);
FORCEADD OFFPAGE..4
(12800 3900);
FORCEPROP 2 LAST $XR1 21 
J 0
(13106 3900);
DISPLAY 0.638298 (13106 3900);
PAINT MONO (13106 3900);
FORCEPROP 2 LAST $XR0 118 
J 0
(12986 3900);
DISPLAY 0.638298 (12986 3900);
PAINT MONO (12986 3900);
FORCEPROP 1 LAST OFFPAGE TRUE
J 0
(13125 3775);
DISPLAY 1.170213 (13125 3775);
PAINT GREEN (13125 3775);
DISPLAY INVISIBLE (13125 3775);
FORCEPROP 2 LAST PATH I132
J 0
(12975 3975);
DISPLAY 1.021277 (12975 3975);
PAINT ORANGE (12975 3975);
DISPLAY INVISIBLE (12975 3975);
FORCEPROP 2 LAST CDS_LIB mstr_standard
J 0
(12800 3900);
PAINT ORANGE (12800 3900);
DISPLAY INVISIBLE (12800 3900);
FORCEPROP 1 LAST COMMENT_BODY TRUE
J 0
(12775 3800);
DISPLAY 1.170213 (12775 3800);
PAINT GREEN (12775 3800);
DISPLAY INVISIBLE (12775 3800);
FORCEADD OFFPAGE..2
(12800 4000);
FORCEPROP 2 LAST $XR0 90 
J 0
(12989 4000);
DISPLAY 0.638298 (12989 4000);
PAINT MONO (12989 4000);
FORCEPROP 2 LAST PATH I133
J 0
(12975 4075);
DISPLAY 1.021277 (12975 4075);
PAINT ORANGE (12975 4075);
DISPLAY INVISIBLE (12975 4075);
FORCEPROP 1 LAST OFFPAGE TRUE
J 0
(13125 3875);
DISPLAY 0.872340 (13125 3875);
PAINT GREEN (13125 3875);
DISPLAY INVISIBLE (13125 3875);
FORCEPROP 2 LAST CDS_LIB mstr_standard
J 0
(12800 4000);
PAINT ORANGE (12800 4000);
DISPLAY INVISIBLE (12800 4000);
FORCEPROP 1 LAST COMMENT_BODY TRUE
J 0
(12755 3905);
DISPLAY 0.872340 (12755 3905);
PAINT GREEN (12755 3905);
DISPLAY INVISIBLE (12755 3905);
FORCEADD OFFPAGE..4
(12800 3850);
FORCEPROP 2 LAST $XR1 21 
J 0
(13106 3850);
DISPLAY 0.638298 (13106 3850);
PAINT MONO (13106 3850);
FORCEPROP 2 LAST $XR0 114 
J 0
(12986 3850);
DISPLAY 0.638298 (12986 3850);
PAINT MONO (12986 3850);
FORCEPROP 1 LAST OFFPAGE TRUE
J 0
(13125 3725);
DISPLAY 1.170213 (13125 3725);
PAINT GREEN (13125 3725);
DISPLAY INVISIBLE (13125 3725);
FORCEPROP 2 LAST PATH I134
J 0
(12975 3925);
DISPLAY 1.021277 (12975 3925);
PAINT ORANGE (12975 3925);
DISPLAY INVISIBLE (12975 3925);
FORCEPROP 2 LAST CDS_LIB mstr_standard
J 0
(12800 3850);
PAINT ORANGE (12800 3850);
DISPLAY INVISIBLE (12800 3850);
FORCEPROP 1 LAST COMMENT_BODY TRUE
J 0
(12775 3750);
DISPLAY 1.170213 (12775 3750);
PAINT GREEN (12775 3750);
DISPLAY INVISIBLE (12775 3750);
FORCEADD OFFPAGE..2
(13575 900);
FORCEPROP 2 LAST $XR3 190 
J 0
(14124 900);
DISPLAY 0.638298 (14124 900);
PAINT MONO (14124 900);
FORCEPROP 2 LAST $XR2 146 
J 0
(14004 900);
DISPLAY 0.638298 (14004 900);
PAINT MONO (14004 900);
FORCEPROP 2 LAST $XR1 118 
J 0
(13884 900);
DISPLAY 0.638298 (13884 900);
PAINT MONO (13884 900);
FORCEPROP 2 LAST $XR0 112 
J 0
(13764 900);
DISPLAY 0.638298 (13764 900);
PAINT MONO (13764 900);
FORCEPROP 1 LAST OFFPAGE TRUE
J 0
(13900 775);
DISPLAY 1.170213 (13900 775);
PAINT GREEN (13900 775);
DISPLAY INVISIBLE (13900 775);
FORCEPROP 2 LAST PATH I135
J 0
(13750 975);
DISPLAY 1.021277 (13750 975);
PAINT ORANGE (13750 975);
DISPLAY INVISIBLE (13750 975);
FORCEPROP 2 LAST CDS_LIB mstr_standard
J 0
(13575 900);
PAINT ORANGE (13575 900);
DISPLAY INVISIBLE (13575 900);
FORCEPROP 1 LAST COMMENT_BODY TRUE
J 0
(13530 805);
DISPLAY 1.170213 (13530 805);
PAINT GREEN (13530 805);
DISPLAY INVISIBLE (13530 805);
FORCEADD OFFPAGE..4
(12225 2300);
FORCEPROP 2 LAST $XR0 90 
J 0
(12411 2300);
DISPLAY 0.638298 (12411 2300);
PAINT MONO (12411 2300);
FORCEPROP 1 LAST OFFPAGE TRUE
J 0
(12550 2175);
DISPLAY 1.170213 (12550 2175);
PAINT GREEN (12550 2175);
DISPLAY INVISIBLE (12550 2175);
FORCEPROP 2 LAST PATH I138
J 0
(12400 2375);
DISPLAY 1.021277 (12400 2375);
PAINT ORANGE (12400 2375);
DISPLAY INVISIBLE (12400 2375);
FORCEPROP 2 LAST CDS_LIB mstr_standard
J 0
(12225 2300);
PAINT ORANGE (12225 2300);
DISPLAY INVISIBLE (12225 2300);
FORCEPROP 1 LAST COMMENT_BODY TRUE
J 0
(12200 2200);
DISPLAY 1.170213 (12200 2200);
PAINT GREEN (12200 2200);
DISPLAY INVISIBLE (12200 2200);
FORCEADD OFFPAGE..4
(12225 2250);
FORCEPROP 2 LAST $XR0 90 
J 0
(12411 2250);
DISPLAY 0.638298 (12411 2250);
PAINT MONO (12411 2250);
FORCEPROP 1 LAST OFFPAGE TRUE
J 0
(12550 2125);
DISPLAY 1.170213 (12550 2125);
PAINT GREEN (12550 2125);
DISPLAY INVISIBLE (12550 2125);
FORCEPROP 2 LAST PATH I139
J 0
(12400 2325);
DISPLAY 1.021277 (12400 2325);
PAINT ORANGE (12400 2325);
DISPLAY INVISIBLE (12400 2325);
FORCEPROP 2 LAST CDS_LIB mstr_standard
J 0
(12225 2250);
PAINT ORANGE (12225 2250);
DISPLAY INVISIBLE (12225 2250);
FORCEPROP 1 LAST COMMENT_BODY TRUE
J 0
(12200 2150);
DISPLAY 1.170213 (12200 2150);
PAINT GREEN (12200 2150);
DISPLAY INVISIBLE (12200 2150);
FORCEADD OFFPAGE..2
(13750 3600);
FORCEPROP 2 LAST $XR2 226 
J 0
(14179 3600);
DISPLAY 0.638298 (14179 3600);
PAINT MONO (14179 3600);
FORCEPROP 2 LAST $XR1 223 
J 0
(14059 3600);
DISPLAY 0.638298 (14059 3600);
PAINT MONO (14059 3600);
FORCEPROP 2 LAST $XR0 193 
J 0
(13939 3600);
DISPLAY 0.638298 (13939 3600);
PAINT MONO (13939 3600);
FORCEPROP 2 LAST PATH I14
J 0
(13925 3675);
DISPLAY 1.021277 (13925 3675);
PAINT ORANGE (13925 3675);
DISPLAY INVISIBLE (13925 3675);
FORCEPROP 1 LAST OFFPAGE TRUE
J 0
(14075 3475);
DISPLAY 1.170213 (14075 3475);
PAINT GREEN (14075 3475);
DISPLAY INVISIBLE (14075 3475);
FORCEPROP 2 LAST CDS_LIB mstr_standard
J 0
(13750 3600);
PAINT MONO (13750 3600);
DISPLAY INVISIBLE (13750 3600);
FORCEPROP 1 LAST COMMENT_BODY TRUE
J 0
(13705 3505);
DISPLAY 1.170213 (13705 3505);
PAINT GREEN (13705 3505);
DISPLAY INVISIBLE (13705 3505);
FORCEADD RES..2
R 2
(6800 2650);
FORCEPROP 1 LASTPIN (6800 2750) $PN 1
J 2
(6795 2712);
DISPLAY 0.617021 (6795 2712);
PAINT ORANGE (6795 2712);
FORCEPROP 1 LAST TOLERANCE 1%
J 2
(6755 2675);
DISPLAY 0.617021 (6755 2675);
PAINT SKYBLUE (6755 2675);
FORCEPROP 1 LASTPIN (6800 2550) $PN 2
J 2
(6795 2560);
DISPLAY 0.617021 (6795 2560);
PAINT ORANGE (6795 2560);
FORCEPROP 1 LAST LOCATION R7P17
J 2
(6755 2775);
DISPLAY 0.617021 (6755 2775);
PAINT AQUA (6755 2775);
FORCEPROP 1 LAST VALUE 90.9
J 2
(6755 2725);
DISPLAY 0.617021 (6755 2725);
PAINT SKYBLUE (6755 2725);
FORCEPROP 1 LAST PACK_TYPE 0402
J 2
(6760 2475);
DISPLAY 0.617021 (6760 2475);
PAINT SKYBLUE (6760 2475);
FORCEPROP 1 LAST MATERIAL CHIP
J 2
(6760 2575);
DISPLAY 0.617021 (6760 2575);
PAINT SKYBLUE (6760 2575);
FORCEPROP 1 LAST PART_NUMBER G21796-365
J 2
(6810 2525);
DISPLAY 0.617021 (6810 2525);
PAINT BLUE (6810 2525);
FORCEPROP 1 LAST WATTAGE 1/16W
J 2
(6760 2625);
DISPLAY 0.617021 (6760 2625);
PAINT SKYBLUE (6760 2625);
FORCEPROP 2 LAST SEC_TYPE 0402
J 0
(6750 2875);
DISPLAY 1.021277 (6750 2875);
PAINT ORANGE (6750 2875);
DISPLAY INVISIBLE (6750 2875);
FORCEPROP 2 LAST ROOM CPU1
J 0
(6775 2825);
PAINT MONO (6775 2825);
DISPLAY INVISIBLE (6775 2825);
FORCEPROP 1 LAST PATH I140
J 2
(6750 2825);
DISPLAY 0.978723 (6750 2825);
PAINT WHITE (6750 2825);
DISPLAY INVISIBLE (6750 2825);
FORCEPROP 2 LAST SEC 1
J 0
(6750 2875);
DISPLAY 0.680851 (6750 2875);
PAINT MONO (6750 2875);
DISPLAY INVISIBLE (6750 2875);
FORCEPROP 2 LAST BOM_COST PROC_SOCKET
J 0
(6775 2875);
PAINT MONO (6775 2875);
DISPLAY INVISIBLE (6775 2875);
FORCEPROP 2 LAST CDS_LOCATION R7P17
J 2
(6755 2775);
DISPLAY 0.617021 (6755 2775);
PAINT AQUA (6755 2775);
DISPLAY INVISIBLE (6755 2775);
FORCEPROP 2 LAST CDS_LIB mstr_discrete
J 0
(6800 2650);
PAINT ORANGE (6800 2650);
DISPLAY INVISIBLE (6800 2650);
FORCEADD OFFPAGE..4
(12525 1750);
FORCEPROP 2 LAST $XR0 97 
J 0
(12711 1750);
DISPLAY 0.638298 (12711 1750);
PAINT MONO (12711 1750);
FORCEPROP 1 LAST OFFPAGE TRUE
J 0
(12850 1625);
DISPLAY 1.170213 (12850 1625);
PAINT GREEN (12850 1625);
DISPLAY INVISIBLE (12850 1625);
FORCEPROP 2 LAST PATH I145
J 0
(12700 1825);
DISPLAY 1.021277 (12700 1825);
PAINT ORANGE (12700 1825);
DISPLAY INVISIBLE (12700 1825);
FORCEPROP 2 LAST CDS_LIB mstr_standard
J 0
(12525 1750);
PAINT ORANGE (12525 1750);
DISPLAY INVISIBLE (12525 1750);
FORCEPROP 1 LAST COMMENT_BODY TRUE
J 0
(12500 1650);
DISPLAY 1.170213 (12500 1650);
PAINT GREEN (12500 1650);
DISPLAY INVISIBLE (12500 1650);
FORCEADD OFFPAGE..4
(12525 1550);
FORCEPROP 2 LAST $XR0 90 
J 0
(12711 1550);
DISPLAY 0.638298 (12711 1550);
PAINT MONO (12711 1550);
FORCEPROP 1 LAST OFFPAGE TRUE
J 0
(12850 1425);
DISPLAY 1.170213 (12850 1425);
PAINT GREEN (12850 1425);
DISPLAY INVISIBLE (12850 1425);
FORCEPROP 2 LAST PATH I146
J 0
(12700 1625);
DISPLAY 1.021277 (12700 1625);
PAINT ORANGE (12700 1625);
DISPLAY INVISIBLE (12700 1625);
FORCEPROP 2 LAST CDS_LIB mstr_standard
J 0
(12525 1550);
PAINT ORANGE (12525 1550);
DISPLAY INVISIBLE (12525 1550);
FORCEPROP 1 LAST COMMENT_BODY TRUE
J 0
(12500 1450);
DISPLAY 1.170213 (12500 1450);
PAINT GREEN (12500 1450);
DISPLAY INVISIBLE (12500 1450);
FORCEADD OFFPAGE..5
(7950 3050);
FORCEPROP 2 LAST $XR0 100 
J 0
(7695 3050);
DISPLAY 0.638298 (7695 3050);
PAINT MONO (7695 3050);
FORCEPROP 1 LAST OFFPAGE TRUE
J 0
(8275 2925);
DISPLAY 1.170213 (8275 2925);
PAINT GREEN (8275 2925);
DISPLAY INVISIBLE (8275 2925);
FORCEPROP 2 LAST PATH I148
J 0
(8000 3125);
DISPLAY 1.021277 (8000 3125);
PAINT ORANGE (8000 3125);
DISPLAY INVISIBLE (8000 3125);
FORCEPROP 2 LAST CDS_LIB mstr_standard
J 0
(7950 3050);
PAINT ORANGE (7950 3050);
DISPLAY INVISIBLE (7950 3050);
FORCEPROP 1 LAST COMMENT_BODY TRUE
J 0
(8050 2975);
DISPLAY 1.170213 (8050 2975);
PAINT GREEN (8050 2975);
DISPLAY INVISIBLE (8050 2975);
FORCEADD OFFPAGE..5
(7950 3100);
FORCEPROP 2 LAST $XR0 100 
J 0
(7695 3100);
DISPLAY 0.638298 (7695 3100);
PAINT MONO (7695 3100);
FORCEPROP 1 LAST OFFPAGE TRUE
J 0
(8275 2975);
DISPLAY 1.170213 (8275 2975);
PAINT GREEN (8275 2975);
DISPLAY INVISIBLE (8275 2975);
FORCEPROP 2 LAST PATH I149
J 0
(8000 3175);
DISPLAY 1.021277 (8000 3175);
PAINT ORANGE (8000 3175);
DISPLAY INVISIBLE (8000 3175);
FORCEPROP 2 LAST CDS_LIB mstr_standard
J 0
(7950 3100);
PAINT ORANGE (7950 3100);
DISPLAY INVISIBLE (7950 3100);
FORCEPROP 1 LAST COMMENT_BODY TRUE
J 0
(8050 3025);
DISPLAY 1.170213 (8050 3025);
PAINT GREEN (8050 3025);
DISPLAY INVISIBLE (8050 3025);
FORCEADD OFFPAGE..4
(13750 3550);
FORCEPROP 2 LAST $XR2 226 
J 0
(14176 3550);
DISPLAY 0.638298 (14176 3550);
PAINT MONO (14176 3550);
FORCEPROP 2 LAST $XR1 223 
J 0
(14056 3550);
DISPLAY 0.638298 (14056 3550);
PAINT MONO (14056 3550);
FORCEPROP 2 LAST $XR0 193 
J 0
(13936 3550);
DISPLAY 0.638298 (13936 3550);
PAINT MONO (13936 3550);
FORCEPROP 2 LAST PATH I15
J 0
(13925 3625);
DISPLAY 1.021277 (13925 3625);
PAINT ORANGE (13925 3625);
DISPLAY INVISIBLE (13925 3625);
FORCEPROP 1 LAST OFFPAGE TRUE
J 0
(14075 3425);
DISPLAY 1.170213 (14075 3425);
PAINT GREEN (14075 3425);
DISPLAY INVISIBLE (14075 3425);
FORCEPROP 2 LAST CDS_LIB mstr_standard
J 0
(13750 3550);
PAINT MONO (13750 3550);
DISPLAY INVISIBLE (13750 3550);
FORCEPROP 1 LAST COMMENT_BODY TRUE
J 0
(13725 3450);
DISPLAY 1.170213 (13725 3450);
PAINT GREEN (13725 3450);
DISPLAY INVISIBLE (13725 3450);
FORCEADD OFFPAGE..5
(7950 3200);
FORCEPROP 2 LAST $XR0 100 
J 0
(7695 3200);
DISPLAY 0.638298 (7695 3200);
PAINT MONO (7695 3200);
FORCEPROP 1 LAST OFFPAGE TRUE
J 0
(8275 3075);
DISPLAY 1.170213 (8275 3075);
PAINT GREEN (8275 3075);
DISPLAY INVISIBLE (8275 3075);
FORCEPROP 2 LAST PATH I150
J 0
(8000 3275);
DISPLAY 1.021277 (8000 3275);
PAINT ORANGE (8000 3275);
DISPLAY INVISIBLE (8000 3275);
FORCEPROP 2 LAST CDS_LIB mstr_standard
J 0
(7950 3200);
PAINT ORANGE (7950 3200);
DISPLAY INVISIBLE (7950 3200);
FORCEPROP 1 LAST COMMENT_BODY TRUE
J 0
(8050 3125);
DISPLAY 1.170213 (8050 3125);
PAINT GREEN (8050 3125);
DISPLAY INVISIBLE (8050 3125);
FORCEADD OFFPAGE..5
(7950 3250);
FORCEPROP 2 LAST $XR0 100 
J 0
(7695 3250);
DISPLAY 0.638298 (7695 3250);
PAINT MONO (7695 3250);
FORCEPROP 1 LAST OFFPAGE TRUE
J 0
(8275 3125);
DISPLAY 1.170213 (8275 3125);
PAINT GREEN (8275 3125);
DISPLAY INVISIBLE (8275 3125);
FORCEPROP 2 LAST PATH I151
J 0
(8000 3325);
DISPLAY 1.021277 (8000 3325);
PAINT ORANGE (8000 3325);
DISPLAY INVISIBLE (8000 3325);
FORCEPROP 2 LAST CDS_LIB mstr_standard
J 0
(7950 3250);
PAINT ORANGE (7950 3250);
DISPLAY INVISIBLE (7950 3250);
FORCEPROP 1 LAST COMMENT_BODY TRUE
J 0
(8050 3175);
DISPLAY 1.170213 (8050 3175);
PAINT GREEN (8050 3175);
DISPLAY INVISIBLE (8050 3175);
FORCEADD SOCKET_P_MECH_A..1
(6875 4000);
FORCEPROP 1 LAST LOCATION XRU2
J 0
(6525 4075);
DISPLAY 0.617021 (6525 4075);
PAINT AQUA (6525 4075);
FORCEPROP 1 LAST SKT_NUMBER P0
J 0
(6550 3975);
DISPLAY 0.808511 (6550 3975);
PAINT GREEN (6550 3975);
FORCEPROP 1 LAST MATERIAL PLASTIC
J 0
(6525 4125);
DISPLAY 0.617021 (6525 4125);
PAINT SKYBLUE (6525 4125);
FORCEPROP 1 LAST PACK_TYPE RIGHT
J 0
(6980 3975);
DISPLAY 0.617021 (6980 3975);
PAINT SKYBLUE (6980 3975);
FORCEPROP 1 LAST PART_NUMBER H37604-101
J 0
(6525 3900);
DISPLAY 0.617021 (6525 3900);
PAINT BLUE (6525 3900);
FORCEPROP 1 LAST PATH I152
J 0
(6875 4120);
DISPLAY 0.872340 (6875 4120);
PAINT WHITE (6875 4120);
DISPLAY INVISIBLE (6875 4120);
FORCEPROP 0 LAST BOM_COST PROC_SOCKET
J 0
(6525 4325);
DISPLAY 1.021277 (6525 4325);
PAINT ORANGE (6525 4325);
DISPLAY INVISIBLE (6525 4325);
FORCEPROP 0 LAST ROOM CPU1
J 0
(6525 4225);
DISPLAY 1.021277 (6525 4225);
PAINT ORANGE (6525 4225);
DISPLAY INVISIBLE (6525 4225);
FORCEPROP 2 LAST CDS_LOCATION XRU2
J 0
(6525 4075);
DISPLAY 0.617021 (6525 4075);
PAINT AQUA (6525 4075);
DISPLAY INVISIBLE (6525 4075);
FORCEPROP 2 LAST CDS_LIB chpset_lib
J 0
(6875 4000);
PAINT ORANGE (6875 4000);
DISPLAY INVISIBLE (6875 4000);
FORCEADD SOCKET_P_MECH_A..1
(6875 3725);
FORCEPROP 1 LAST PACK_TYPE LEFT
J 0
(6980 3700);
DISPLAY 0.617021 (6980 3700);
PAINT SKYBLUE (6980 3700);
FORCEPROP 1 LAST PART_NUMBER H37604-201
J 0
(6525 3625);
DISPLAY 0.617021 (6525 3625);
PAINT BLUE (6525 3625);
FORCEPROP 1 LAST LOCATION XLU2
J 0
(6525 3800);
DISPLAY 0.617021 (6525 3800);
PAINT AQUA (6525 3800);
FORCEPROP 1 LAST SKT_NUMBER P0
J 0
(6550 3700);
DISPLAY 0.808511 (6550 3700);
PAINT GREEN (6550 3700);
FORCEPROP 1 LAST MATERIAL PLASTIC
J 0
(6525 3850);
DISPLAY 0.617021 (6525 3850);
PAINT SKYBLUE (6525 3850);
FORCEPROP 1 LAST PATH I153
J 0
(6875 3845);
DISPLAY 0.872340 (6875 3845);
PAINT WHITE (6875 3845);
DISPLAY INVISIBLE (6875 3845);
FORCEPROP 2 LAST CDS_LIB chpset_lib
J 0
(6875 3725);
PAINT ORANGE (6875 3725);
DISPLAY INVISIBLE (6875 3725);
FORCEPROP 0 LAST ROOM CPU1
J 0
(6525 3950);
DISPLAY 1.021277 (6525 3950);
PAINT ORANGE (6525 3950);
DISPLAY INVISIBLE (6525 3950);
FORCEPROP 2 LAST CDS_LOCATION XLU2
J 0
(6525 3800);
DISPLAY 0.617021 (6525 3800);
PAINT AQUA (6525 3800);
DISPLAY INVISIBLE (6525 3800);
FORCEPROP 0 LAST BOM_COST PROC_SOCKET
J 0
(6525 4050);
DISPLAY 1.021277 (6525 4050);
PAINT ORANGE (6525 4050);
DISPLAY INVISIBLE (6525 4050);
FORCEADD RES..2
R 2
(7500 1425);
FORCEPROP 1 LASTPIN (7500 1325) $PN 2
J 2
(7495 1335);
DISPLAY 0.617021 (7495 1335);
PAINT ORANGE (7495 1335);
FORCEPROP 1 LAST PACK_TYPE 0402
J 2
(7460 1250);
DISPLAY 0.617021 (7460 1250);
PAINT SKYBLUE (7460 1250);
FORCEPROP 1 LAST PART_NUMBER G21796-047
J 2
(7510 1300);
DISPLAY 0.617021 (7510 1300);
PAINT BLUE (7510 1300);
FORCEPROP 1 LASTPIN (7500 1525) $PN 1
J 2
(7495 1487);
DISPLAY 0.617021 (7495 1487);
PAINT ORANGE (7495 1487);
FORCEPROP 1 LAST MATERIAL CHIP
J 2
(7460 1350);
DISPLAY 0.617021 (7460 1350);
PAINT SKYBLUE (7460 1350);
FORCEPROP 1 LAST WATTAGE 1/16W
J 2
(7460 1400);
DISPLAY 0.617021 (7460 1400);
PAINT SKYBLUE (7460 1400);
FORCEPROP 1 LAST TOLERANCE 1%
J 2
(7455 1450);
DISPLAY 0.617021 (7455 1450);
PAINT SKYBLUE (7455 1450);
FORCEPROP 1 LAST VALUE 49.9
J 2
(7455 1500);
DISPLAY 0.617021 (7455 1500);
PAINT SKYBLUE (7455 1500);
FORCEPROP 1 LAST LOCATION R3D4
J 2
(7455 1550);
DISPLAY 0.617021 (7455 1550);
PAINT AQUA (7455 1550);
FORCEPROP 2 LAST SEC_TYPE 0402
J 0
(7450 1650);
DISPLAY 1.021277 (7450 1650);
PAINT ORANGE (7450 1650);
DISPLAY INVISIBLE (7450 1650);
FORCEPROP 2 LAST BOM_COST PROC_SOCKET
J 0
(7475 1650);
PAINT MONO (7475 1650);
DISPLAY INVISIBLE (7475 1650);
FORCEPROP 2 LAST SEC 1
J 0
(7450 1650);
DISPLAY 0.680851 (7450 1650);
PAINT MONO (7450 1650);
DISPLAY INVISIBLE (7450 1650);
FORCEPROP 2 LAST CDS_LOCATION R3D4
J 2
(7455 1550);
DISPLAY 0.617021 (7455 1550);
PAINT AQUA (7455 1550);
DISPLAY INVISIBLE (7455 1550);
FORCEPROP 1 LAST PATH I155
J 2
(7450 1600);
DISPLAY 0.978723 (7450 1600);
PAINT WHITE (7450 1600);
DISPLAY INVISIBLE (7450 1600);
FORCEPROP 2 LAST ROOM CPU1
J 0
(7475 1600);
PAINT MONO (7475 1600);
DISPLAY INVISIBLE (7475 1600);
FORCEPROP 2 LAST CDS_LIB mstr_discrete
J 0
(7500 1425);
PAINT ORANGE (7500 1425);
DISPLAY INVISIBLE (7500 1425);
FORCEADD RES..1
(12100 3850);
FORCEPROP 1 LAST PACK_TYPE 0402
J 0
(12350 3800);
DISPLAY 0.617021 (12350 3800);
PAINT SKYBLUE (12350 3800);
FORCEPROP 1 LASTPIN (12200 3850) $PN 2
J 0
(12162 3862);
DISPLAY 0.617021 (12162 3862);
PAINT ORANGE (12162 3862);
FORCEPROP 1 LAST WATTAGE 1/16W
J 2
(12200 3800);
DISPLAY 0.617021 (12200 3800);
PAINT SKYBLUE (12200 3800);
FORCEPROP 1 LASTPIN (12000 3850) $PN 1
J 0
(12012 3862);
DISPLAY 0.617021 (12012 3862);
PAINT ORANGE (12012 3862);
FORCEPROP 1 LAST TOLERANCE 1%
J 0
(12000 3800);
DISPLAY 0.617021 (12000 3800);
PAINT SKYBLUE (12000 3800);
FORCEPROP 1 LAST VALUE 49.9
J 2
(11975 3800);
DISPLAY 0.617021 (11975 3800);
PAINT SKYBLUE (11975 3800);
FORCEPROP 1 LAST LOCATION R7P26
J 0
(11750 3800);
DISPLAY 0.617021 (11750 3800);
PAINT AQUA (11750 3800);
FORCEPROP 1 LAST PART_NUMBER G21796-047
J 0
(12475 3800);
DISPLAY 0.617021 (12475 3800);
PAINT BLUE (12475 3800);
FORCEPROP 1 LAST MATERIAL CHIP
J 0
(12225 3800);
DISPLAY 0.617021 (12225 3800);
PAINT SKYBLUE (12225 3800);
FORCEPROP 2 LAST SEC_TYPE 0402
J 0
(12050 4050);
DISPLAY 1.021277 (12050 4050);
PAINT ORANGE (12050 4050);
DISPLAY INVISIBLE (12050 4050);
FORCEPROP 2 LAST BOM_COST PROC_SOCKET
J 0
(12075 4050);
PAINT MONO (12075 4050);
DISPLAY INVISIBLE (12075 4050);
FORCEPROP 2 LAST SEC 1
J 0
(12050 4050);
DISPLAY 0.680851 (12050 4050);
PAINT MONO (12050 4050);
DISPLAY INVISIBLE (12050 4050);
FORCEPROP 2 LAST ROOM CPU1
J 0
(12075 4000);
PAINT MONO (12075 4000);
DISPLAY INVISIBLE (12075 4000);
FORCEPROP 1 LAST PATH I156
J 0
(12050 4000);
DISPLAY 0.978723 (12050 4000);
PAINT WHITE (12050 4000);
DISPLAY INVISIBLE (12050 4000);
FORCEPROP 2 LAST CDS_LOCATION R7P26
J 0
(12075 3950);
DISPLAY 0.617021 (12075 3950);
PAINT AQUA (12075 3950);
DISPLAY INVISIBLE (12075 3950);
FORCEPROP 2 LAST CDS_LIB mstr_discrete
J 0
(12100 3850);
PAINT ORANGE (12100 3850);
DISPLAY INVISIBLE (12100 3850);
FORCEADD RES..2
(12600 2300);
FORCEPROP 1 LAST MATERIAL CHIP
J 0
(12690 2225);
DISPLAY 0.617021 (12690 2225);
PAINT SKYBLUE (12690 2225);
FORCEPROP 1 LAST WATTAGE 1/16W
J 0
(12690 2275);
DISPLAY 0.617021 (12690 2275);
PAINT SKYBLUE (12690 2275);
FORCEPROP 1 LAST VALUE 1.8K
J 0
(12695 2375);
DISPLAY 0.617021 (12695 2375);
PAINT SKYBLUE (12695 2375);
FORCEPROP 1 LAST PACK_TYPE 0402
J 0
(12690 2175);
DISPLAY 0.617021 (12690 2175);
PAINT SKYBLUE (12690 2175);
FORCEPROP 1 LAST TOLERANCE 1%
J 0
(12695 2325);
DISPLAY 0.617021 (12695 2325);
PAINT SKYBLUE (12695 2325);
FORCEPROP 1 LAST LOCATION R8N1
J 2
(12775 2425);
DISPLAY 0.617021 (12775 2425);
PAINT AQUA (12775 2425);
FORCEPROP 1 LASTPIN (12600 2400) $PN 1
J 0
(12605 2362);
DISPLAY 0.617021 (12605 2362);
PAINT ORANGE (12605 2362);
FORCEPROP 1 LAST PART_NUMBER G21796-336
R 1
J 0
(12665 2175);
DISPLAY 0.617021 (12665 2175);
PAINT BLUE (12665 2175);
FORCEPROP 1 LASTPIN (12600 2200) $PN 2
J 0
(12605 2210);
DISPLAY 0.617021 (12605 2210);
PAINT ORANGE (12605 2210);
FORCEPROP 2 LAST SEC_TYPE 0402
J 0
(12650 2525);
DISPLAY 1.021277 (12650 2525);
PAINT ORANGE (12650 2525);
DISPLAY INVISIBLE (12650 2525);
FORCEPROP 2 LAST BOM_COST PROC_SOCKET
J 0
(12750 2525);
PAINT MONO (12750 2525);
DISPLAY INVISIBLE (12750 2525);
FORCEPROP 2 LAST ROOM CPU1
J 0
(12750 2475);
PAINT MONO (12750 2475);
DISPLAY INVISIBLE (12750 2475);
FORCEPROP 2 LAST CDS_LOCATION R8N1
J 2
(12750 2425);
DISPLAY 0.617021 (12750 2425);
PAINT AQUA (12750 2425);
DISPLAY INVISIBLE (12750 2425);
FORCEPROP 2 LAST SEC 1
J 0
(12650 2525);
DISPLAY 0.680851 (12650 2525);
PAINT MONO (12650 2525);
DISPLAY INVISIBLE (12650 2525);
FORCEPROP 1 LAST PATH I157
J 0
(12650 2475);
DISPLAY 0.978723 (12650 2475);
PAINT WHITE (12650 2475);
DISPLAY INVISIBLE (12650 2475);
FORCEPROP 2 LAST CDS_LIB mstr_discrete
J 0
(12600 2300);
PAINT ORANGE (12600 2300);
DISPLAY INVISIBLE (12600 2300);
FORCEADD RES..2
(12850 2300);
FORCEPROP 1 LAST LOCATION R8N4
J 0
(12945 2425);
DISPLAY 0.617021 (12945 2425);
PAINT AQUA (12945 2425);
FORCEPROP 1 LAST VALUE 1.8K
J 0
(12945 2375);
DISPLAY 0.617021 (12945 2375);
PAINT SKYBLUE (12945 2375);
FORCEPROP 1 LAST WATTAGE 1/16W
J 0
(12940 2275);
DISPLAY 0.617021 (12940 2275);
PAINT SKYBLUE (12940 2275);
FORCEPROP 1 LAST MATERIAL CHIP
J 0
(12940 2225);
DISPLAY 0.617021 (12940 2225);
PAINT SKYBLUE (12940 2225);
FORCEPROP 1 LAST PACK_TYPE 0402
J 0
(12940 2175);
DISPLAY 0.617021 (12940 2175);
PAINT SKYBLUE (12940 2175);
FORCEPROP 1 LAST TOLERANCE 1%
J 0
(12945 2325);
DISPLAY 0.617021 (12945 2325);
PAINT SKYBLUE (12945 2325);
FORCEPROP 1 LASTPIN (12850 2400) $PN 1
J 0
(12855 2362);
DISPLAY 0.617021 (12855 2362);
PAINT ORANGE (12855 2362);
FORCEPROP 1 LASTPIN (12850 2200) $PN 2
J 0
(12855 2210);
DISPLAY 0.617021 (12855 2210);
PAINT ORANGE (12855 2210);
FORCEPROP 1 LAST PART_NUMBER G21796-336
R 1
J 0
(12915 2175);
DISPLAY 0.617021 (12915 2175);
PAINT BLUE (12915 2175);
FORCEPROP 2 LAST SEC_TYPE 0402
J 0
(12900 2525);
DISPLAY 1.021277 (12900 2525);
PAINT ORANGE (12900 2525);
DISPLAY INVISIBLE (12900 2525);
FORCEPROP 2 LAST BOM_COST PROC_SOCKET
J 0
(12900 2525);
PAINT MONO (12900 2525);
DISPLAY INVISIBLE (12900 2525);
FORCEPROP 2 LAST SEC 1
J 0
(12900 2525);
DISPLAY 0.680851 (12900 2525);
PAINT MONO (12900 2525);
DISPLAY INVISIBLE (12900 2525);
FORCEPROP 2 LAST ROOM CPU1
J 0
(12900 2475);
PAINT MONO (12900 2475);
DISPLAY INVISIBLE (12900 2475);
FORCEPROP 1 LAST PATH I158
J 0
(12900 2475);
DISPLAY 0.978723 (12900 2475);
PAINT WHITE (12900 2475);
DISPLAY INVISIBLE (12900 2475);
FORCEPROP 2 LAST CDS_LOCATION R8N4
J 0
(12895 2425);
DISPLAY 0.617021 (12895 2425);
PAINT AQUA (12895 2425);
DISPLAY INVISIBLE (12895 2425);
FORCEPROP 2 LAST CDS_LIB mstr_discrete
J 0
(12850 2300);
PAINT ORANGE (12850 2300);
DISPLAY INVISIBLE (12850 2300);
FORCEADD RES..2
(13100 2300);
FORCEPROP 1 LAST VALUE 10.0K
J 0
(13195 2375);
DISPLAY 0.617021 (13195 2375);
PAINT SKYBLUE (13195 2375);
FORCEPROP 1 LAST WATTAGE 1/16W
J 0
(13190 2275);
DISPLAY 0.617021 (13190 2275);
PAINT SKYBLUE (13190 2275);
FORCEPROP 1 LAST TOLERANCE 1%
J 0
(13195 2325);
DISPLAY 0.617021 (13195 2325);
PAINT SKYBLUE (13195 2325);
FORCEPROP 1 LAST LOCATION R8N3
J 0
(13195 2425);
DISPLAY 0.617021 (13195 2425);
PAINT AQUA (13195 2425);
FORCEPROP 1 LASTPIN (13100 2400) $PN 1
J 0
(13105 2362);
DISPLAY 0.617021 (13105 2362);
PAINT ORANGE (13105 2362);
FORCEPROP 1 LAST PART_NUMBER G21796-016
R 1
J 0
(13165 2175);
DISPLAY 0.617021 (13165 2175);
PAINT BLUE (13165 2175);
FORCEPROP 1 LASTPIN (13100 2200) $PN 2
J 0
(13105 2210);
DISPLAY 0.617021 (13105 2210);
PAINT ORANGE (13105 2210);
FORCEPROP 1 LAST MATERIAL CHIP
J 0
(13190 2225);
DISPLAY 0.617021 (13190 2225);
PAINT SKYBLUE (13190 2225);
FORCEPROP 1 LAST PACK_TYPE 0402
J 0
(13190 2175);
DISPLAY 0.617021 (13190 2175);
PAINT SKYBLUE (13190 2175);
FORCEPROP 2 LAST SEC_TYPE 0402
J 0
(13150 2525);
DISPLAY 1.021277 (13150 2525);
PAINT ORANGE (13150 2525);
DISPLAY INVISIBLE (13150 2525);
FORCEPROP 2 LAST BOM_COST PROC_SOCKET
J 0
(13150 2525);
PAINT MONO (13150 2525);
DISPLAY INVISIBLE (13150 2525);
FORCEPROP 2 LAST SEC 1
J 0
(13150 2525);
DISPLAY 0.680851 (13150 2525);
PAINT MONO (13150 2525);
DISPLAY INVISIBLE (13150 2525);
FORCEPROP 2 LAST ROOM CPU1
J 0
(13150 2475);
PAINT MONO (13150 2475);
DISPLAY INVISIBLE (13150 2475);
FORCEPROP 1 LAST PATH I159
J 0
(13150 2475);
DISPLAY 0.978723 (13150 2475);
PAINT WHITE (13150 2475);
DISPLAY INVISIBLE (13150 2475);
FORCEPROP 2 LAST CDS_LOCATION R8N3
J 0
(13145 2425);
DISPLAY 0.617021 (13145 2425);
PAINT AQUA (13145 2425);
DISPLAY INVISIBLE (13145 2425);
FORCEPROP 2 LAST CDS_LIB mstr_discrete
J 0
(13100 2300);
PAINT ORANGE (13100 2300);
DISPLAY INVISIBLE (13100 2300);
FORCEADD OFFPAGE..2
(13750 3450);
FORCEPROP 2 LAST $XR2 213 
J 0
(14179 3450);
DISPLAY 0.638298 (14179 3450);
PAINT MONO (14179 3450);
FORCEPROP 2 LAST $XR1 206 
J 0
(14059 3450);
DISPLAY 0.638298 (14059 3450);
PAINT MONO (14059 3450);
FORCEPROP 2 LAST $XR0 193 
J 0
(13939 3450);
DISPLAY 0.638298 (13939 3450);
PAINT MONO (13939 3450);
FORCEPROP 2 LAST PATH I16
J 0
(13925 3525);
DISPLAY 1.021277 (13925 3525);
PAINT ORANGE (13925 3525);
DISPLAY INVISIBLE (13925 3525);
FORCEPROP 1 LAST OFFPAGE TRUE
J 0
(14075 3325);
DISPLAY 1.170213 (14075 3325);
PAINT GREEN (14075 3325);
DISPLAY INVISIBLE (14075 3325);
FORCEPROP 2 LAST CDS_LIB mstr_standard
J 0
(13750 3450);
PAINT MONO (13750 3450);
DISPLAY INVISIBLE (13750 3450);
FORCEPROP 1 LAST COMMENT_BODY TRUE
J 0
(13705 3355);
DISPLAY 1.170213 (13705 3355);
PAINT GREEN (13705 3355);
DISPLAY INVISIBLE (13705 3355);
FORCEADD RES..2
(13350 2300);
FORCEPROP 1 LAST WATTAGE 1/16W
J 0
(13440 2275);
DISPLAY 0.617021 (13440 2275);
PAINT SKYBLUE (13440 2275);
FORCEPROP 1 LAST VALUE 10.0K
J 0
(13445 2375);
DISPLAY 0.617021 (13445 2375);
PAINT SKYBLUE (13445 2375);
FORCEPROP 1 LAST LOCATION R8N5
J 0
(13445 2425);
DISPLAY 0.617021 (13445 2425);
PAINT AQUA (13445 2425);
FORCEPROP 1 LAST TOLERANCE 1%
J 0
(13445 2325);
DISPLAY 0.617021 (13445 2325);
PAINT SKYBLUE (13445 2325);
FORCEPROP 1 LASTPIN (13350 2400) $PN 1
J 0
(13355 2362);
DISPLAY 0.617021 (13355 2362);
PAINT ORANGE (13355 2362);
FORCEPROP 1 LAST PART_NUMBER G21796-016
R 1
J 0
(13415 2175);
DISPLAY 0.617021 (13415 2175);
PAINT BLUE (13415 2175);
FORCEPROP 1 LAST PACK_TYPE 0402
J 0
(13440 2175);
DISPLAY 0.617021 (13440 2175);
PAINT SKYBLUE (13440 2175);
FORCEPROP 1 LASTPIN (13350 2200) $PN 2
J 0
(13355 2210);
DISPLAY 0.617021 (13355 2210);
PAINT ORANGE (13355 2210);
FORCEPROP 1 LAST MATERIAL CHIP
J 0
(13440 2225);
DISPLAY 0.617021 (13440 2225);
PAINT SKYBLUE (13440 2225);
FORCEPROP 2 LAST SEC_TYPE 0402
J 0
(13400 2525);
DISPLAY 1.021277 (13400 2525);
PAINT ORANGE (13400 2525);
DISPLAY INVISIBLE (13400 2525);
FORCEPROP 2 LAST BOM_COST PROC_SOCKET
J 0
(13400 2525);
PAINT MONO (13400 2525);
DISPLAY INVISIBLE (13400 2525);
FORCEPROP 2 LAST ROOM CPU1
J 0
(13400 2475);
PAINT MONO (13400 2475);
DISPLAY INVISIBLE (13400 2475);
FORCEPROP 1 LAST PATH I160
J 0
(13400 2475);
DISPLAY 0.978723 (13400 2475);
PAINT WHITE (13400 2475);
DISPLAY INVISIBLE (13400 2475);
FORCEPROP 2 LAST SEC 1
J 0
(13400 2525);
DISPLAY 0.680851 (13400 2525);
PAINT MONO (13400 2525);
DISPLAY INVISIBLE (13400 2525);
FORCEPROP 2 LAST CDS_LOCATION R8N5
J 0
(13395 2425);
DISPLAY 0.617021 (13395 2425);
PAINT AQUA (13395 2425);
DISPLAY INVISIBLE (13395 2425);
FORCEPROP 2 LAST CDS_LIB mstr_discrete
J 0
(13350 2300);
PAINT ORANGE (13350 2300);
DISPLAY INVISIBLE (13350 2300);
FORCEADD RES..2
(13600 2300);
FORCEPROP 1 LAST VALUE 10.0K
J 0
(13695 2375);
DISPLAY 0.617021 (13695 2375);
PAINT SKYBLUE (13695 2375);
FORCEPROP 1 LAST LOCATION R8N2
J 0
(13695 2425);
DISPLAY 0.617021 (13695 2425);
PAINT AQUA (13695 2425);
FORCEPROP 1 LAST TOLERANCE 1%
J 0
(13695 2325);
DISPLAY 0.617021 (13695 2325);
PAINT SKYBLUE (13695 2325);
FORCEPROP 1 LASTPIN (13600 2400) $PN 1
J 0
(13605 2362);
DISPLAY 0.617021 (13605 2362);
PAINT ORANGE (13605 2362);
FORCEPROP 1 LAST PART_NUMBER G21796-016
R 1
J 0
(13665 2175);
DISPLAY 0.617021 (13665 2175);
PAINT BLUE (13665 2175);
FORCEPROP 1 LAST PACK_TYPE 0402
J 0
(13690 2175);
DISPLAY 0.617021 (13690 2175);
PAINT SKYBLUE (13690 2175);
FORCEPROP 1 LAST MATERIAL CHIP
J 0
(13690 2225);
DISPLAY 0.617021 (13690 2225);
PAINT SKYBLUE (13690 2225);
FORCEPROP 1 LASTPIN (13600 2200) $PN 2
J 0
(13605 2210);
DISPLAY 0.617021 (13605 2210);
PAINT ORANGE (13605 2210);
FORCEPROP 1 LAST WATTAGE 1/16W
J 0
(13690 2275);
DISPLAY 0.617021 (13690 2275);
PAINT SKYBLUE (13690 2275);
FORCEPROP 2 LAST BOM_COST PROC_SOCKET
J 0
(13650 2525);
PAINT MONO (13650 2525);
DISPLAY INVISIBLE (13650 2525);
FORCEPROP 2 LAST SEC_TYPE 0402
J 0
(13650 2525);
DISPLAY 1.021277 (13650 2525);
PAINT ORANGE (13650 2525);
DISPLAY INVISIBLE (13650 2525);
FORCEPROP 2 LAST ROOM CPU1
J 0
(13650 2475);
PAINT MONO (13650 2475);
DISPLAY INVISIBLE (13650 2475);
FORCEPROP 1 LAST PATH I161
J 0
(13650 2475);
DISPLAY 0.978723 (13650 2475);
PAINT WHITE (13650 2475);
DISPLAY INVISIBLE (13650 2475);
FORCEPROP 2 LAST SEC 1
J 0
(13650 2525);
DISPLAY 0.680851 (13650 2525);
PAINT MONO (13650 2525);
DISPLAY INVISIBLE (13650 2525);
FORCEPROP 2 LAST CDS_LOCATION R8N2
J 0
(13645 2425);
DISPLAY 0.617021 (13645 2425);
PAINT AQUA (13645 2425);
DISPLAY INVISIBLE (13645 2425);
FORCEPROP 2 LAST CDS_LIB mstr_discrete
J 0
(13600 2300);
PAINT ORANGE (13600 2300);
DISPLAY INVISIBLE (13600 2300);
FORCEADD P3V3_STBY..1
(13600 2600);
FORCEPROP 3 LASTPIN (13600 2550) SIG_NAME P3V3_STBY\g
J 0
(13610 2560);
DISPLAY 0.659574 (13610 2560);
PAINT MONO (13610 2560);
DISPLAY INVISIBLE (13610 2560);
FORCEPROP 2 LAST CDS_LIB mstr_symbols
J 0
(13600 2600);
PAINT ORANGE (13600 2600);
DISPLAY INVISIBLE (13600 2600);
FORCEPROP 1 LAST SIZE 1B
J 0
(13645 2622);
DISPLAY 0.340426 (13645 2622);
PAINT GREEN (13645 2622);
DISPLAY INVISIBLE (13645 2622);
FORCEPROP 1 LAST PATH I162
J 0
(13645 2602);
DISPLAY 0.340426 (13645 2602);
PAINT GREEN (13645 2602);
DISPLAY INVISIBLE (13645 2602);
FORCEPROP 1 LAST VOLTAGE 3.3V
J 0
(13555 2557);
DISPLAY 0.340426 (13555 2557);
PAINT SKYBLUE (13555 2557);
DISPLAY INVISIBLE (13555 2557);
FORCEPROP 1 LAST BODY_TYPE PLUMBING
J 0
(13555 2557);
DISPLAY 0.340426 (13555 2557);
PAINT GREEN (13555 2557);
DISPLAY INVISIBLE (13555 2557);
FORCEPROP 1 LAST HDL_POWER P3V3_STBY
J 0
(13300 2475);
DISPLAY 0.872340 (13300 2475);
PAINT GREEN (13300 2475);
DISPLAY INVISIBLE (13300 2475);
FORCEADD OFFPAGE..2
(13750 2100);
FORCEPROP 2 LAST $XR0 191 
J 0
(13939 2100);
DISPLAY 0.638298 (13939 2100);
PAINT MONO (13939 2100);
FORCEPROP 2 LAST PATH I163
J 0
(13925 2175);
DISPLAY 1.021277 (13925 2175);
PAINT ORANGE (13925 2175);
DISPLAY INVISIBLE (13925 2175);
FORCEPROP 2 LAST CDS_LIB mstr_standard
J 0
(13750 2100);
PAINT ORANGE (13750 2100);
DISPLAY INVISIBLE (13750 2100);
FORCEPROP 1 LAST COMMENT_BODY TRUE
J 0
(13705 2005);
DISPLAY 1.170213 (13705 2005);
PAINT GREEN (13705 2005);
DISPLAY INVISIBLE (13705 2005);
FORCEPROP 1 LAST OFFPAGE TRUE
J 0
(14075 1975);
DISPLAY 1.170213 (14075 1975);
PAINT GREEN (14075 1975);
DISPLAY INVISIBLE (14075 1975);
FORCEADD OFFPAGE..2
(13750 2050);
FORCEPROP 2 LAST $XR0 191 
J 0
(13939 2050);
DISPLAY 0.638298 (13939 2050);
PAINT MONO (13939 2050);
FORCEPROP 2 LAST PATH I164
J 0
(13925 2125);
DISPLAY 1.021277 (13925 2125);
PAINT ORANGE (13925 2125);
DISPLAY INVISIBLE (13925 2125);
FORCEPROP 2 LAST CDS_LIB mstr_standard
J 0
(13750 2050);
PAINT ORANGE (13750 2050);
DISPLAY INVISIBLE (13750 2050);
FORCEPROP 1 LAST OFFPAGE TRUE
J 0
(14075 1925);
DISPLAY 1.170213 (14075 1925);
PAINT GREEN (14075 1925);
DISPLAY INVISIBLE (14075 1925);
FORCEPROP 1 LAST COMMENT_BODY TRUE
J 0
(13705 1955);
DISPLAY 1.170213 (13705 1955);
PAINT GREEN (13705 1955);
DISPLAY INVISIBLE (13705 1955);
FORCEADD OFFPAGE..2
(13750 1950);
FORCEPROP 2 LAST $XR0 190 
J 0
(13939 1950);
DISPLAY 0.638298 (13939 1950);
PAINT MONO (13939 1950);
FORCEPROP 2 LAST PATH I165
J 0
(13925 2025);
DISPLAY 1.021277 (13925 2025);
PAINT ORANGE (13925 2025);
DISPLAY INVISIBLE (13925 2025);
FORCEPROP 1 LAST OFFPAGE TRUE
J 0
(14075 1825);
DISPLAY 1.170213 (14075 1825);
PAINT GREEN (14075 1825);
DISPLAY INVISIBLE (14075 1825);
FORCEPROP 2 LAST CDS_LIB mstr_standard
J 0
(13750 1950);
PAINT ORANGE (13750 1950);
DISPLAY INVISIBLE (13750 1950);
FORCEPROP 1 LAST COMMENT_BODY TRUE
J 0
(13705 1855);
DISPLAY 1.170213 (13705 1855);
PAINT GREEN (13705 1855);
DISPLAY INVISIBLE (13705 1855);
FORCEADD OFFPAGE..2
(13750 1900);
FORCEPROP 2 LAST $XR1 190 
J 0
(14059 1900);
DISPLAY 0.638298 (14059 1900);
PAINT MONO (14059 1900);
FORCEPROP 2 LAST $XR0 113 
J 0
(13939 1900);
DISPLAY 0.638298 (13939 1900);
PAINT MONO (13939 1900);
FORCEPROP 2 LAST PATH I166
J 0
(13925 1975);
DISPLAY 1.021277 (13925 1975);
PAINT ORANGE (13925 1975);
DISPLAY INVISIBLE (13925 1975);
FORCEPROP 1 LAST OFFPAGE TRUE
J 0
(14075 1775);
DISPLAY 1.170213 (14075 1775);
PAINT GREEN (14075 1775);
DISPLAY INVISIBLE (14075 1775);
FORCEPROP 2 LAST CDS_LIB mstr_standard
J 0
(13750 1900);
PAINT ORANGE (13750 1900);
DISPLAY INVISIBLE (13750 1900);
FORCEPROP 1 LAST COMMENT_BODY TRUE
J 0
(13705 1805);
DISPLAY 1.170213 (13705 1805);
PAINT GREEN (13705 1805);
DISPLAY INVISIBLE (13705 1805);
FORCEADD OFFPAGE..2
(13750 1850);
FORCEPROP 2 LAST $XR0 190 
J 0
(13939 1850);
DISPLAY 0.638298 (13939 1850);
PAINT MONO (13939 1850);
FORCEPROP 2 LAST PATH I167
J 0
(13925 1925);
DISPLAY 1.021277 (13925 1925);
PAINT ORANGE (13925 1925);
DISPLAY INVISIBLE (13925 1925);
FORCEPROP 1 LAST OFFPAGE TRUE
J 0
(14075 1725);
DISPLAY 1.170213 (14075 1725);
PAINT GREEN (14075 1725);
DISPLAY INVISIBLE (14075 1725);
FORCEPROP 2 LAST CDS_LIB mstr_standard
J 0
(13750 1850);
PAINT ORANGE (13750 1850);
DISPLAY INVISIBLE (13750 1850);
FORCEPROP 1 LAST COMMENT_BODY TRUE
J 0
(13705 1755);
DISPLAY 1.170213 (13705 1755);
PAINT GREEN (13705 1755);
DISPLAY INVISIBLE (13705 1755);
FORCEADD P3V3_STBY..1
(13275 1325);
FORCEPROP 3 LASTPIN (13275 1275) SIG_NAME P3V3_STBY\g
J 0
(13285 1285);
DISPLAY 0.659574 (13285 1285);
PAINT MONO (13285 1285);
DISPLAY INVISIBLE (13285 1285);
FORCEPROP 1 LAST SIZE 1B
J 0
(13320 1347);
DISPLAY 0.340426 (13320 1347);
PAINT GREEN (13320 1347);
DISPLAY INVISIBLE (13320 1347);
FORCEPROP 1 LAST PATH I169
J 0
(13320 1327);
DISPLAY 0.340426 (13320 1327);
PAINT GREEN (13320 1327);
DISPLAY INVISIBLE (13320 1327);
FORCEPROP 1 LAST VOLTAGE 3.3V
J 0
(13230 1282);
DISPLAY 0.340426 (13230 1282);
PAINT SKYBLUE (13230 1282);
DISPLAY INVISIBLE (13230 1282);
FORCEPROP 2 LAST CDS_LIB mstr_symbols
J 0
(13275 1325);
PAINT ORANGE (13275 1325);
DISPLAY INVISIBLE (13275 1325);
FORCEPROP 1 LAST BODY_TYPE PLUMBING
J 0
(13230 1282);
DISPLAY 0.340426 (13230 1282);
PAINT GREEN (13230 1282);
DISPLAY INVISIBLE (13230 1282);
FORCEPROP 1 LAST HDL_POWER P3V3_STBY
J 0
(12975 1200);
DISPLAY 0.872340 (12975 1200);
PAINT GREEN (12975 1200);
DISPLAY INVISIBLE (12975 1200);
FORCEADD OFFPAGE..3
(13725 3500);
FORCEPROP 2 LAST $XR2 213 
J 0
(14179 3500);
DISPLAY 0.638298 (14179 3500);
PAINT MONO (14179 3500);
FORCEPROP 2 LAST $XR1 206 
J 0
(14059 3500);
DISPLAY 0.638298 (14059 3500);
PAINT MONO (14059 3500);
FORCEPROP 2 LAST $XR0 193 
J 0
(13939 3500);
DISPLAY 0.638298 (13939 3500);
PAINT MONO (13939 3500);
FORCEPROP 2 LAST PATH I17
J 0
(13925 3575);
DISPLAY 1.021277 (13925 3575);
PAINT ORANGE (13925 3575);
DISPLAY INVISIBLE (13925 3575);
FORCEPROP 1 LAST OFFPAGE TRUE
J 0
(14050 3375);
DISPLAY 1.170213 (14050 3375);
PAINT GREEN (14050 3375);
DISPLAY INVISIBLE (14050 3375);
FORCEPROP 2 LAST CDS_LIB mstr_standard
J 0
(13725 3500);
PAINT MONO (13725 3500);
DISPLAY INVISIBLE (13725 3500);
FORCEPROP 1 LAST COMMENT_BODY TRUE
J 0
(13675 3400);
DISPLAY 1.170213 (13675 3400);
PAINT GREEN (13675 3400);
DISPLAY INVISIBLE (13675 3400);
FORCEADD RES..1
(12100 3900);
FORCEPROP 1 LASTPIN (12200 3900) $PN 2
J 0
(12162 3912);
DISPLAY 0.617021 (12162 3912);
PAINT ORANGE (12162 3912);
FORCEPROP 1 LAST TOLERANCE 1%
J 0
(12000 3950);
DISPLAY 0.617021 (12000 3950);
PAINT SKYBLUE (12000 3950);
FORCEPROP 1 LAST VALUE 49.9
J 2
(11975 3950);
DISPLAY 0.617021 (11975 3950);
PAINT SKYBLUE (11975 3950);
FORCEPROP 1 LAST LOCATION R7P25
J 0
(11750 3950);
DISPLAY 0.617021 (11750 3950);
PAINT AQUA (11750 3950);
FORCEPROP 1 LASTPIN (12000 3900) $PN 1
J 0
(12012 3912);
DISPLAY 0.617021 (12012 3912);
PAINT ORANGE (12012 3912);
FORCEPROP 1 LAST WATTAGE 1/16W
J 2
(12200 3950);
DISPLAY 0.617021 (12200 3950);
PAINT SKYBLUE (12200 3950);
FORCEPROP 1 LAST MATERIAL CHIP
J 0
(12225 3950);
DISPLAY 0.617021 (12225 3950);
PAINT SKYBLUE (12225 3950);
FORCEPROP 1 LAST PACK_TYPE 0402
J 0
(12350 3950);
DISPLAY 0.617021 (12350 3950);
PAINT SKYBLUE (12350 3950);
FORCEPROP 1 LAST PART_NUMBER G21796-047
J 0
(12475 3950);
DISPLAY 0.617021 (12475 3950);
PAINT BLUE (12475 3950);
FORCEPROP 2 LAST SEC 1
J 0
(12050 4100);
DISPLAY 0.680851 (12050 4100);
PAINT MONO (12050 4100);
DISPLAY INVISIBLE (12050 4100);
FORCEPROP 2 LAST SEC_TYPE 0402
J 0
(12050 4100);
DISPLAY 1.021277 (12050 4100);
PAINT ORANGE (12050 4100);
DISPLAY INVISIBLE (12050 4100);
FORCEPROP 2 LAST BOM_COST PROC_SOCKET
J 0
(12075 4025);
PAINT MONO (12075 4025);
DISPLAY INVISIBLE (12075 4025);
FORCEPROP 1 LAST PATH I170
J 0
(12050 4050);
DISPLAY 0.978723 (12050 4050);
PAINT WHITE (12050 4050);
DISPLAY INVISIBLE (12050 4050);
FORCEPROP 2 LAST ROOM CPU1
J 0
(12075 3975);
PAINT MONO (12075 3975);
DISPLAY INVISIBLE (12075 3975);
FORCEPROP 2 LAST CDS_LIB mstr_discrete
J 0
(12100 3900);
PAINT ORANGE (12100 3900);
DISPLAY INVISIBLE (12100 3900);
FORCEPROP 2 LAST CDS_LOCATION R7P25
J 0
(12025 3950);
DISPLAY 0.617021 (12025 3950);
PAINT AQUA (12025 3950);
DISPLAY INVISIBLE (12025 3950);
FORCEADD SKX_EXT_B..1
(10225 2500);
FORCEPROP 2 LASTPIN (9275 3850) $PN CU26
J 2
(9265 3860);
DISPLAY 0.617021 (9265 3860);
PAINT ORANGE (9265 3860);
FORCEPROP 2 LASTPIN (11175 4100) $PN AP21
J 0
(11185 4110);
DISPLAY 0.617021 (11185 4110);
PAINT ORANGE (11185 4110);
FORCEPROP 2 LASTPIN (11175 4150) $PN BC24
J 0
(11185 4160);
DISPLAY 0.617021 (11185 4160);
PAINT ORANGE (11185 4160);
FORCEPROP 1 LAST MATERIAL IC
J 0
(9325 4350);
DISPLAY 0.617021 (9325 4350);
PAINT SKYBLUE (9325 4350);
FORCEPROP 1 LAST LOCATION U2D1
J 0
(9325 4400);
DISPLAY 0.617021 (9325 4400);
PAINT AQUA (9325 4400);
FORCEPROP 2 LASTPIN (9275 4150) $PN AW24
J 2
(9265 4160);
DISPLAY 0.617021 (9265 4160);
PAINT ORANGE (9265 4160);
FORCEPROP 2 LASTPIN (9275 4100) $PN AU24
J 2
(9265 4110);
DISPLAY 0.617021 (9265 4110);
PAINT ORANGE (9265 4110);
FORCEPROP 2 LASTPIN (11175 3550) $PN DL44
J 0
(11185 3560);
DISPLAY 0.617021 (11185 3560);
PAINT ORANGE (11185 3560);
FORCEPROP 2 LASTPIN (11175 3600) $PN DG44
J 0
(11185 3610);
DISPLAY 0.617021 (11185 3610);
PAINT ORANGE (11185 3610);
FORCEPROP 2 LASTPIN (11175 3650) $PN DJ44
J 0
(11185 3660);
DISPLAY 0.617021 (11185 3660);
PAINT ORANGE (11185 3660);
FORCEPROP 2 LASTPIN (11175 2500) $PN AV15
J 0
(11185 2510);
DISPLAY 0.617021 (11185 2510);
PAINT ORANGE (11185 2510);
FORCEPROP 2 LASTPIN (11175 2550) $PN AW18
J 0
(11185 2560);
DISPLAY 0.617021 (11185 2560);
PAINT ORANGE (11185 2560);
FORCEPROP 2 LASTPIN (11175 2800) $PN AB15
J 0
(11185 2810);
DISPLAY 0.617021 (11185 2810);
PAINT ORANGE (11185 2810);
FORCEPROP 2 LASTPIN (11175 3500) $PN DB45
J 0
(11185 3510);
DISPLAY 0.617021 (11185 3510);
PAINT ORANGE (11185 3510);
FORCEPROP 2 LASTPIN (11175 3450) $PN DC44
J 0
(11185 3460);
DISPLAY 0.617021 (11185 3460);
PAINT ORANGE (11185 3460);
FORCEPROP 2 LASTPIN (11175 3400) $PN DE44
J 0
(11185 3410);
DISPLAY 0.617021 (11185 3410);
PAINT ORANGE (11185 3410);
FORCEPROP 2 LASTPIN (11175 2200) $PN AU20
J 0
(11185 2210);
DISPLAY 0.617021 (11185 2210);
PAINT ORANGE (11185 2210);
FORCEPROP 2 LASTPIN (11175 2300) $PN AU16
J 0
(11185 2310);
DISPLAY 0.617021 (11185 2310);
PAINT ORANGE (11185 2310);
FORCEPROP 2 LASTPIN (11175 2250) $PN AU22
J 0
(11185 2260);
DISPLAY 0.617021 (11185 2260);
PAINT ORANGE (11185 2260);
FORCEPROP 2 LASTPIN (11175 2700) $PN AR18
J 0
(11185 2710);
DISPLAY 0.617021 (11185 2710);
PAINT ORANGE (11185 2710);
FORCEPROP 2 LASTPIN (11175 2850) $PN AC16
J 0
(11185 2860);
DISPLAY 0.617021 (11185 2860);
PAINT ORANGE (11185 2860);
FORCEPROP 2 LASTPIN (11175 2100) $PN DB71
J 0
(11185 2110);
DISPLAY 0.617021 (11185 2110);
PAINT ORANGE (11185 2110);
FORCEPROP 2 LASTPIN (11175 2050) $PN CY71
J 0
(11185 2060);
DISPLAY 0.617021 (11185 2060);
PAINT ORANGE (11185 2060);
FORCEPROP 2 LASTPIN (11175 3900) $PN AR14
J 0
(11185 3910);
DISPLAY 0.617021 (11185 3910);
PAINT ORANGE (11185 3910);
FORCEPROP 2 LASTPIN (11175 2400) $PN AF15
J 0
(11185 2410);
DISPLAY 0.617021 (11185 2410);
PAINT ORANGE (11185 2410);
FORCEPROP 2 LASTPIN (11175 3750) $PN AU12
J 0
(11185 3760);
DISPLAY 0.617021 (11185 3760);
PAINT ORANGE (11185 3760);
FORCEPROP 2 LASTPIN (11175 3000) $PN AN20
J 0
(11185 3010);
DISPLAY 0.617021 (11185 3010);
PAINT ORANGE (11185 3010);
FORCEPROP 2 LASTPIN (11175 2650) $PN AV17
J 0
(11185 2660);
DISPLAY 0.617021 (11185 2660);
PAINT ORANGE (11185 2660);
FORCEPROP 2 LASTPIN (11175 4000) $PN AJ14
J 0
(11185 4010);
DISPLAY 0.617021 (11185 4010);
PAINT ORANGE (11185 4010);
FORCEPROP 2 LASTPIN (11175 2600) $PN BD23
J 0
(11185 2610);
DISPLAY 0.617021 (11185 2610);
PAINT ORANGE (11185 2610);
FORCEPROP 2 LASTPIN (11175 2450) $PN BA20
J 0
(11185 2460);
DISPLAY 0.617021 (11185 2460);
PAINT ORANGE (11185 2460);
FORCEPROP 2 LASTPIN (11175 3100) $PN AJ12
J 0
(11185 3110);
DISPLAY 0.617021 (11185 3110);
PAINT ORANGE (11185 3110);
FORCEPROP 2 LASTPIN (11175 2900) $PN AB17
J 0
(11185 2910);
DISPLAY 0.617021 (11185 2910);
PAINT ORANGE (11185 2910);
FORCEPROP 2 LASTPIN (11175 1300) $PN AW14
J 0
(11185 1310);
DISPLAY 0.617021 (11185 1310);
PAINT ORANGE (11185 1310);
FORCEPROP 2 LASTPIN (11175 1250) $PN DC50
J 0
(11185 1260);
DISPLAY 0.617021 (11185 1260);
PAINT ORANGE (11185 1260);
FORCEPROP 2 LASTPIN (11175 1150) $PN AY19
J 0
(11185 1160);
DISPLAY 0.617021 (11185 1160);
PAINT ORANGE (11185 1160);
FORCEPROP 2 LASTPIN (11175 800) $PN AE14
J 0
(11185 810);
DISPLAY 0.617021 (11185 810);
PAINT ORANGE (11185 810);
FORCEPROP 2 LASTPIN (11175 1700) $PN CV59
J 0
(11185 1710);
DISPLAY 0.617021 (11185 1710);
PAINT ORANGE (11185 1710);
FORCEPROP 2 LASTPIN (11175 900) $PN AB13
J 0
(11185 910);
DISPLAY 0.617021 (11185 910);
PAINT ORANGE (11185 910);
FORCEPROP 2 LASTPIN (11175 1050) $PN AR12
J 0
(11185 1060);
DISPLAY 0.617021 (11185 1060);
PAINT ORANGE (11185 1060);
FORCEPROP 2 LASTPIN (11175 1000) $PN AG16
J 0
(11185 1010);
DISPLAY 0.617021 (11185 1010);
PAINT ORANGE (11185 1010);
FORCEPROP 2 LASTPIN (11175 1900) $PN CW72
J 0
(11185 1910);
DISPLAY 0.617021 (11185 1910);
PAINT ORANGE (11185 1910);
FORCEPROP 2 LASTPIN (11175 1850) $PN DC72
J 0
(11185 1860);
DISPLAY 0.617021 (11185 1860);
PAINT ORANGE (11185 1860);
FORCEPROP 2 LASTPIN (11175 1400) $PN CV57
J 0
(11185 1410);
DISPLAY 0.617021 (11185 1410);
PAINT ORANGE (11185 1410);
FORCEPROP 2 LASTPIN (11175 1350) $PN CU58
J 0
(11185 1360);
DISPLAY 0.617021 (11185 1360);
PAINT ORANGE (11185 1360);
FORCEPROP 2 LASTPIN (11175 1600) $PN AP11
J 0
(11185 1610);
DISPLAY 0.617021 (11185 1610);
PAINT ORANGE (11185 1610);
FORCEPROP 2 LASTPIN (11175 1550) $PN AE20
J 0
(11185 1560);
DISPLAY 0.617021 (11185 1560);
PAINT ORANGE (11185 1560);
FORCEPROP 2 LASTPIN (11175 1450) $PN CW56
J 0
(11185 1460);
DISPLAY 0.617021 (11185 1460);
PAINT ORANGE (11185 1460);
FORCEPROP 2 LASTPIN (9275 2100) $PN CW58
J 2
(9265 2110);
DISPLAY 0.617021 (9265 2110);
PAINT ORANGE (9265 2110);
FORCEPROP 2 LASTPIN (9275 2150) $PN CT59
J 2
(9265 2160);
DISPLAY 0.617021 (9265 2160);
PAINT ORANGE (9265 2160);
FORCEPROP 2 LASTPIN (9275 2250) $PN AL18
J 2
(9265 2260);
DISPLAY 0.617021 (9265 2260);
PAINT ORANGE (9265 2260);
FORCEPROP 2 LASTPIN (9275 2300) $PN AM19
J 2
(9265 2310);
DISPLAY 0.617021 (9265 2310);
PAINT ORANGE (9265 2310);
FORCEPROP 2 LASTPIN (9275 3350) $PN AF13
J 2
(9265 3360);
DISPLAY 0.617021 (9265 3360);
PAINT ORANGE (9265 3360);
FORCEPROP 2 LASTPIN (9275 3400) $PN AH13
J 2
(9265 3410);
DISPLAY 0.617021 (9265 3410);
PAINT ORANGE (9265 3410);
FORCEPROP 2 LASTPIN (9275 3500) $PN DV63
J 2
(9265 3510);
DISPLAY 0.617021 (9265 3510);
PAINT ORANGE (9265 3510);
FORCEPROP 2 LASTPIN (9275 2750) $PN DD49
J 2
(9265 2760);
DISPLAY 0.617021 (9265 2760);
PAINT ORANGE (9265 2760);
FORCEPROP 2 LASTPIN (9275 2650) $PN DC48
J 2
(9265 2660);
DISPLAY 0.617021 (9265 2660);
PAINT ORANGE (9265 2660);
FORCEPROP 2 LASTPIN (9275 3650) $PN CR28
J 2
(9265 3660);
DISPLAY 0.617021 (9265 3660);
PAINT ORANGE (9265 3660);
FORCEPROP 2 LASTPIN (9275 2500) $PN AF17
J 2
(9265 2510);
DISPLAY 0.617021 (9265 2510);
PAINT ORANGE (9265 2510);
FORCEPROP 2 LASTPIN (9275 2400) $PN AJ18
J 2
(9265 2410);
DISPLAY 0.617021 (9265 2410);
PAINT ORANGE (9265 2410);
FORCEPROP 2 LASTPIN (9275 2900) $PN AC42
J 2
(9265 2910);
DISPLAY 0.617021 (9265 2910);
PAINT ORANGE (9265 2910);
FORCEPROP 2 LASTPIN (9275 2850) $PN AB43
J 2
(9265 2860);
DISPLAY 0.617021 (9265 2860);
PAINT ORANGE (9265 2860);
FORCEPROP 2 LASTPIN (9275 2800) $PN Y43
J 2
(9265 2810);
DISPLAY 0.617021 (9265 2810);
PAINT ORANGE (9265 2810);
FORCEPROP 2 LASTPIN (9275 3700) $PN AN30
J 2
(9265 3710);
DISPLAY 0.617021 (9265 3710);
PAINT ORANGE (9265 3710);
FORCEPROP 2 LASTPIN (9275 3250) $PN CV61
J 2
(9265 3260);
DISPLAY 0.617021 (9265 3260);
PAINT ORANGE (9265 3260);
FORCEPROP 2 LASTPIN (9275 3200) $PN CT61
J 2
(9265 3210);
DISPLAY 0.617021 (9265 3210);
PAINT ORANGE (9265 3210);
FORCEPROP 2 LASTPIN (9275 3000) $PN AJ64
J 2
(9265 3010);
DISPLAY 0.617021 (9265 3010);
PAINT ORANGE (9265 3010);
FORCEPROP 2 LASTPIN (9275 3800) $PN CT25
J 2
(9265 3810);
DISPLAY 0.617021 (9265 3810);
PAINT ORANGE (9265 3810);
FORCEPROP 2 LASTPIN (9275 4000) $PN CP27
J 2
(9265 4010);
DISPLAY 0.617021 (9265 4010);
PAINT ORANGE (9265 4010);
FORCEPROP 2 LASTPIN (9275 3950) $PN CR26
J 2
(9265 3960);
DISPLAY 0.617021 (9265 3960);
PAINT ORANGE (9265 3960);
FORCEPROP 2 LASTPIN (9275 3150) $PN CP61
J 2
(9265 3160);
DISPLAY 0.617021 (9265 3160);
PAINT ORANGE (9265 3160);
FORCEPROP 2 LASTPIN (9275 3100) $PN AH63
J 2
(9265 3110);
DISPLAY 0.617021 (9265 3110);
PAINT ORANGE (9265 3110);
FORCEPROP 2 LASTPIN (9275 3050) $PN AK63
J 2
(9265 3060);
DISPLAY 0.617021 (9265 3060);
PAINT ORANGE (9265 3060);
FORCEPROP 2 LASTPIN (9275 2450) $PN AE18
J 2
(9265 2460);
DISPLAY 0.617021 (9265 2460);
PAINT ORANGE (9265 2460);
FORCEPROP 2 LASTPIN (9275 1650) $PN CL28
J 2
(9265 1660);
DISPLAY 0.617021 (9265 1660);
PAINT ORANGE (9265 1660);
FORCEPROP 2 LASTPIN (9275 1800) $PN AP29
J 2
(9265 1810);
DISPLAY 0.617021 (9265 1810);
PAINT ORANGE (9265 1810);
FORCEPROP 2 LASTPIN (9275 1750) $PN AT29
J 2
(9265 1760);
DISPLAY 0.617021 (9265 1760);
PAINT ORANGE (9265 1760);
FORCEPROP 2 LASTPIN (9275 850) $PN Y13
J 2
(9265 860);
DISPLAY 0.617021 (9265 860);
PAINT ORANGE (9265 860);
FORCEPROP 2 LASTPIN (9275 900) $PN W14
J 2
(9265 910);
DISPLAY 0.617021 (9265 910);
PAINT ORANGE (9265 910);
FORCEPROP 2 LASTPIN (9275 1000) $PN AC14
J 2
(9265 1010);
DISPLAY 0.617021 (9265 1010);
PAINT ORANGE (9265 1010);
FORCEPROP 2 LASTPIN (9275 950) $PN AA14
J 2
(9265 960);
DISPLAY 0.617021 (9265 960);
PAINT ORANGE (9265 960);
FORCEPROP 2 LASTPIN (9275 1900) $PN CL30
J 2
(9265 1910);
DISPLAY 0.617021 (9265 1910);
PAINT ORANGE (9265 1910);
FORCEPROP 2 LASTPIN (9275 1850) $PN CN30
J 2
(9265 1860);
DISPLAY 0.617021 (9265 1860);
PAINT ORANGE (9265 1860);
FORCEPROP 2 LASTPIN (9275 2000) $PN CR30
J 2
(9265 2010);
DISPLAY 0.617021 (9265 2010);
PAINT ORANGE (9265 2010);
FORCEPROP 2 LASTPIN (9275 1950) $PN CP29
J 2
(9265 1960);
DISPLAY 0.617021 (9265 1960);
PAINT ORANGE (9265 1960);
FORCEPROP 2 LASTPIN (9275 1600) $PN CT31
J 2
(9265 1610);
DISPLAY 0.617021 (9265 1610);
PAINT ORANGE (9265 1610);
FORCEPROP 2 LASTPIN (9275 1550) $PN CU32
J 2
(9265 1560);
DISPLAY 0.617021 (9265 1560);
PAINT ORANGE (9265 1560);
FORCEPROP 2 LASTPIN (9275 1400) $PN AE12
J 2
(9265 1410);
DISPLAY 0.617021 (9265 1410);
PAINT ORANGE (9265 1410);
FORCEPROP 2 LASTPIN (9275 1350) $PN Y11
J 2
(9265 1360);
DISPLAY 0.617021 (9265 1360);
PAINT ORANGE (9265 1360);
FORCEPROP 2 LASTPIN (9275 1300) $PN AA12
J 2
(9265 1310);
DISPLAY 0.617021 (9265 1310);
PAINT ORANGE (9265 1310);
FORCEPROP 2 LASTPIN (9275 1250) $PN AF11
J 2
(9265 1260);
DISPLAY 0.617021 (9265 1260);
PAINT ORANGE (9265 1260);
FORCEPROP 2 LASTPIN (9275 1100) $PN AJ10
J 2
(9265 1110);
DISPLAY 0.617021 (9265 1110);
PAINT ORANGE (9265 1110);
FORCEPROP 2 LASTPIN (9275 1450) $PN AC12
J 2
(9265 1460);
DISPLAY 0.617021 (9265 1460);
PAINT ORANGE (9265 1460);
FORCEPROP 2 LASTPIN (9275 1200) $PN AG10
J 2
(9265 1210);
DISPLAY 0.617021 (9265 1210);
PAINT ORANGE (9265 1210);
FORCEPROP 2 LASTPIN (9275 1150) $PN AH11
J 2
(9265 1160);
DISPLAY 0.617021 (9265 1160);
PAINT ORANGE (9265 1160);
FORCEPROP 1 LAST PART_NUMBER TBD
J 0
(9325 600);
DISPLAY 0.617021 (9325 600);
PAINT BLUE (9325 600);
FORCEPROP 2 LASTPIN (11175 3850) $PN AT19
J 0
(11185 3860);
DISPLAY 0.617021 (11185 3860);
PAINT ORANGE (11185 3860);
FORCEPROP 2 LASTPIN (11175 3300) $PN AL14
J 0
(11185 3310);
DISPLAY 0.617021 (11185 3310);
PAINT ORANGE (11185 3310);
FORCEPROP 2 LASTPIN (11175 3200) $PN AL12
J 0
(11185 3210);
DISPLAY 0.617021 (11185 3210);
PAINT ORANGE (11185 3210);
FORCEPROP 2 LASTPIN (11175 3150) $PN AK11
J 0
(11185 3160);
DISPLAY 0.617021 (11185 3160);
PAINT ORANGE (11185 3160);
FORCEPROP 2 LASTPIN (11175 1750) $PN AM11
J 0
(11185 1760);
DISPLAY 0.617021 (11185 1760);
PAINT ORANGE (11185 1760);
FORCEPROP 2 LASTPIN (9275 2700) $PN DD47
J 2
(9265 2710);
DISPLAY 0.617021 (9265 2710);
PAINT ORANGE (9265 2710);
FORCEPROP 2 LASTPIN (9275 1700) $PN CK29
J 2
(9265 1710);
DISPLAY 0.617021 (9265 1710);
PAINT ORANGE (9265 1710);
FORCEPROP 2 LASTPIN (11175 1950) $PN DA72
J 0
(11185 1960);
DISPLAY 0.617021 (11185 1960);
PAINT ORANGE (11185 1960);
FORCEPROP 2 LASTPIN (11175 1200) $PN DB51
J 0
(11185 1210);
DISPLAY 0.617021 (11185 1210);
PAINT ORANGE (11185 1210);
FORCEPROP 2 LASTPIN (9275 2550) $PN AD17
J 2
(9265 2560);
DISPLAY 0.617021 (9265 2560);
PAINT ORANGE (9265 2560);
FORCEPROP 2 LASTPIN (9275 3550) $PN U64
J 2
(9265 3560);
DISPLAY 0.617021 (9265 3560);
PAINT ORANGE (9265 3560);
FORCEPROP 1 LAST PATH I172
J 0
(10225 4350);
PAINT GREEN (10225 4350);
DISPLAY INVISIBLE (10225 4350);
FORCEPROP 1 LAST PACK_TYPE BGA1
J 0
(9325 4450);
PAINT SKYBLUE (9325 4450);
DISPLAY INVISIBLE (9325 4450);
FORCEPROP 2 LAST SEC_TYPE BGA1
J 0
(9325 4450);
DISPLAY 1.021277 (9325 4450);
PAINT ORANGE (9325 4450);
DISPLAY INVISIBLE (9325 4450);
FORCEPROP 2 LAST SEC 1
J 0
(9325 4450);
DISPLAY 0.680851 (9325 4450);
PAINT MONO (9325 4450);
DISPLAY INVISIBLE (9325 4450);
FORCEPROP 2 LAST CDS_LOCATION U2D1
J 0
(9325 4400);
DISPLAY 0.617021 (9325 4400);
PAINT AQUA (9325 4400);
DISPLAY INVISIBLE (9325 4400);
FORCEPROP 2 LAST CDS_LIB chpset_lib
J 0
(10225 2500);
PAINT ORANGE (10225 2500);
DISPLAY INVISIBLE (10225 2500);
FORCEPROP 0 LAST ROOM CPU1
J 0
(9325 4500);
DISPLAY 1.021277 (9325 4500);
PAINT ORANGE (9325 4500);
DISPLAY INVISIBLE (9325 4500);
FORCEADD OFFPAGE..5
(8225 2300);
FORCEPROP 2 LAST $XR0 163 
J 0
(7970 2300);
DISPLAY 0.638298 (7970 2300);
PAINT MONO (7970 2300);
FORCEPROP 1 LAST OFFPAGE TRUE
J 0
(8550 2175);
DISPLAY 1.170213 (8550 2175);
PAINT GREEN (8550 2175);
DISPLAY INVISIBLE (8550 2175);
FORCEPROP 2 LAST PATH I173
J 0
(8275 2375);
DISPLAY 1.021277 (8275 2375);
PAINT ORANGE (8275 2375);
DISPLAY INVISIBLE (8275 2375);
FORCEPROP 2 LAST CDS_LIB mstr_standard
J 0
(8225 2300);
PAINT MONO (8225 2300);
DISPLAY INVISIBLE (8225 2300);
FORCEPROP 1 LAST COMMENT_BODY TRUE
J 0
(8325 2225);
DISPLAY 1.170213 (8325 2225);
PAINT GREEN (8325 2225);
DISPLAY INVISIBLE (8325 2225);
FORCEADD OFFPAGE..6
(8250 2250);
FORCEPROP 2 LAST $XR0 163 
J 0
(7970 2250);
DISPLAY 0.638298 (7970 2250);
PAINT MONO (7970 2250);
FORCEPROP 1 LAST OFFPAGE TRUE
J 0
(8575 2125);
DISPLAY 1.170213 (8575 2125);
PAINT GREEN (8575 2125);
DISPLAY INVISIBLE (8575 2125);
FORCEPROP 2 LAST PATH I174
J 0
(8300 2325);
DISPLAY 1.021277 (8300 2325);
PAINT ORANGE (8300 2325);
DISPLAY INVISIBLE (8300 2325);
FORCEPROP 1 LAST COMMENT_BODY TRUE
J 0
(8350 2175);
DISPLAY 1.170213 (8350 2175);
PAINT GREEN (8350 2175);
DISPLAY INVISIBLE (8350 2175);
FORCEPROP 2 LAST CDS_LIB mstr_standard
J 0
(8250 2250);
PAINT MONO (8250 2250);
DISPLAY INVISIBLE (8250 2250);
FORCEADD OFFPAGE..4
(12525 1300);
FORCEPROP 2 LAST $XR0 90 
J 0
(12711 1300);
DISPLAY 0.638298 (12711 1300);
PAINT MONO (12711 1300);
FORCEPROP 1 LAST OFFPAGE TRUE
J 0
(12850 1175);
DISPLAY 1.170213 (12850 1175);
PAINT GREEN (12850 1175);
DISPLAY INVISIBLE (12850 1175);
FORCEPROP 2 LAST PATH I175
J 0
(12700 1375);
DISPLAY 1.021277 (12700 1375);
PAINT ORANGE (12700 1375);
DISPLAY INVISIBLE (12700 1375);
FORCEPROP 2 LAST CDS_LIB mstr_standard
J 0
(12525 1300);
PAINT MONO (12525 1300);
DISPLAY INVISIBLE (12525 1300);
FORCEPROP 1 LAST COMMENT_BODY TRUE
J 0
(12500 1200);
DISPLAY 1.170213 (12500 1200);
PAINT GREEN (12500 1200);
DISPLAY INVISIBLE (12500 1200);
FORCEADD OFFPAGE..4
(12525 1250);
FORCEPROP 2 LAST $XR0 90 
J 0
(12711 1250);
DISPLAY 0.638298 (12711 1250);
PAINT MONO (12711 1250);
FORCEPROP 1 LAST OFFPAGE TRUE
J 0
(12850 1125);
DISPLAY 1.170213 (12850 1125);
PAINT GREEN (12850 1125);
DISPLAY INVISIBLE (12850 1125);
FORCEPROP 2 LAST PATH I178
J 0
(12700 1325);
DISPLAY 1.021277 (12700 1325);
PAINT ORANGE (12700 1325);
DISPLAY INVISIBLE (12700 1325);
FORCEPROP 2 LAST CDS_LIB mstr_standard
J 0
(12525 1250);
PAINT ORANGE (12525 1250);
DISPLAY INVISIBLE (12525 1250);
FORCEPROP 1 LAST COMMENT_BODY TRUE
J 0
(12500 1150);
DISPLAY 1.170213 (12500 1150);
PAINT GREEN (12500 1150);
DISPLAY INVISIBLE (12500 1150);
FORCEADD OFFPAGE..4
(12525 1200);
FORCEPROP 2 LAST $XR0 90 
J 0
(12711 1200);
DISPLAY 0.638298 (12711 1200);
PAINT MONO (12711 1200);
FORCEPROP 1 LAST OFFPAGE TRUE
J 0
(12850 1075);
DISPLAY 1.170213 (12850 1075);
PAINT GREEN (12850 1075);
DISPLAY INVISIBLE (12850 1075);
FORCEPROP 2 LAST PATH I179
J 0
(12700 1275);
DISPLAY 1.021277 (12700 1275);
PAINT ORANGE (12700 1275);
DISPLAY INVISIBLE (12700 1275);
FORCEPROP 2 LAST CDS_LIB mstr_standard
J 0
(12525 1200);
PAINT ORANGE (12525 1200);
DISPLAY INVISIBLE (12525 1200);
FORCEPROP 1 LAST COMMENT_BODY TRUE
J 0
(12500 1100);
DISPLAY 1.170213 (12500 1100);
PAINT GREEN (12500 1100);
DISPLAY INVISIBLE (12500 1100);
FORCEADD OFFPAGE..4
(13750 3400);
FORCEPROP 2 LAST $XR2 213 
J 0
(14176 3400);
DISPLAY 0.638298 (14176 3400);
PAINT MONO (14176 3400);
FORCEPROP 2 LAST $XR1 206 
J 0
(14056 3400);
DISPLAY 0.638298 (14056 3400);
PAINT MONO (14056 3400);
FORCEPROP 2 LAST $XR0 193 
J 0
(13936 3400);
DISPLAY 0.638298 (13936 3400);
PAINT MONO (13936 3400);
FORCEPROP 2 LAST PATH I18
J 0
(13925 3475);
DISPLAY 1.021277 (13925 3475);
PAINT ORANGE (13925 3475);
DISPLAY INVISIBLE (13925 3475);
FORCEPROP 1 LAST OFFPAGE TRUE
J 0
(14075 3275);
DISPLAY 1.170213 (14075 3275);
PAINT GREEN (14075 3275);
DISPLAY INVISIBLE (14075 3275);
FORCEPROP 2 LAST CDS_LIB mstr_standard
J 0
(13750 3400);
PAINT MONO (13750 3400);
DISPLAY INVISIBLE (13750 3400);
FORCEPROP 1 LAST COMMENT_BODY TRUE
J 0
(13725 3300);
DISPLAY 1.170213 (13725 3300);
PAINT GREEN (13725 3300);
DISPLAY INVISIBLE (13725 3300);
FORCEADD OFFPAGE..4
(12525 1150);
FORCEPROP 2 LAST $XR0 90 
J 0
(12711 1150);
DISPLAY 0.638298 (12711 1150);
PAINT MONO (12711 1150);
FORCEPROP 1 LAST OFFPAGE TRUE
J 0
(12850 1025);
DISPLAY 1.170213 (12850 1025);
PAINT GREEN (12850 1025);
DISPLAY INVISIBLE (12850 1025);
FORCEPROP 2 LAST PATH I180
J 0
(12700 1225);
DISPLAY 1.021277 (12700 1225);
PAINT ORANGE (12700 1225);
DISPLAY INVISIBLE (12700 1225);
FORCEPROP 2 LAST CDS_LIB mstr_standard
J 0
(12525 1150);
PAINT ORANGE (12525 1150);
DISPLAY INVISIBLE (12525 1150);
FORCEPROP 1 LAST COMMENT_BODY TRUE
J 0
(12500 1050);
DISPLAY 1.170213 (12500 1050);
PAINT GREEN (12500 1050);
DISPLAY INVISIBLE (12500 1050);
FORCEADD RES..2
(13275 1100);
FORCEPROP 1 LAST LOCATION R6P39
J 0
(13320 1225);
DISPLAY 0.617021 (13320 1225);
PAINT AQUA (13320 1225);
FORCEPROP 1 LAST VALUE 4.75K
J 0
(13320 1175);
DISPLAY 0.617021 (13320 1175);
PAINT SKYBLUE (13320 1175);
FORCEPROP 1 LAST TOLERANCE 1%
J 0
(13320 1125);
DISPLAY 0.617021 (13320 1125);
PAINT SKYBLUE (13320 1125);
FORCEPROP 1 LAST MATERIAL CHIP
J 0
(13315 1025);
DISPLAY 0.617021 (13315 1025);
PAINT SKYBLUE (13315 1025);
FORCEPROP 1 LAST WATTAGE 1/16W
J 0
(13315 1075);
DISPLAY 0.617021 (13315 1075);
PAINT SKYBLUE (13315 1075);
FORCEPROP 1 LAST PART_NUMBER G21796-072
J 0
(13315 975);
DISPLAY 0.617021 (13315 975);
PAINT BLUE (13315 975);
FORCEPROP 1 LAST PACK_TYPE 0402
J 0
(13315 925);
DISPLAY 0.617021 (13315 925);
PAINT SKYBLUE (13315 925);
FORCEPROP 1 LASTPIN (13275 1200) $PN 1
J 0
(13280 1162);
DISPLAY 0.617021 (13280 1162);
PAINT ORANGE (13280 1162);
FORCEPROP 1 LASTPIN (13275 1000) $PN 2
J 0
(13280 1010);
DISPLAY 0.617021 (13280 1010);
PAINT ORANGE (13280 1010);
FORCEPROP 2 LAST SEC_TYPE 0402
J 0
(13325 1325);
DISPLAY 1.021277 (13325 1325);
PAINT ORANGE (13325 1325);
DISPLAY INVISIBLE (13325 1325);
FORCEPROP 2 LAST SEC 1
J 0
(13325 1325);
DISPLAY 0.680851 (13325 1325);
PAINT MONO (13325 1325);
DISPLAY INVISIBLE (13325 1325);
FORCEPROP 2 LAST CDS_LOCATION R6P39
J 0
(13320 1225);
DISPLAY 0.617021 (13320 1225);
PAINT AQUA (13320 1225);
DISPLAY INVISIBLE (13320 1225);
FORCEPROP 1 LAST PATH I181
J 0
(13325 1275);
DISPLAY 0.978723 (13325 1275);
PAINT WHITE (13325 1275);
DISPLAY INVISIBLE (13325 1275);
FORCEPROP 0 LAST ROOM CPU1
J 0
(13325 1325);
DISPLAY 1.021277 (13325 1325);
PAINT ORANGE (13325 1325);
DISPLAY INVISIBLE (13325 1325);
FORCEPROP 2 LAST CDS_LIB mstr_discrete
J 0
(13275 1100);
PAINT ORANGE (13275 1100);
DISPLAY INVISIBLE (13275 1100);
FORCEADD OFFPAGE..6
(7975 1450);
FORCEPROP 2 LAST $XR1 112 
J 0
(7606 1450);
DISPLAY 0.638298 (7606 1450);
PAINT MONO (7606 1450);
FORCEPROP 2 LAST $XR0 21 
J 0
(7726 1450);
DISPLAY 0.638298 (7726 1450);
PAINT MONO (7726 1450);
FORCEPROP 1 LAST OFFPAGE TRUE
J 0
(8300 1325);
DISPLAY 1.170213 (8300 1325);
PAINT GREEN (8300 1325);
DISPLAY INVISIBLE (8300 1325);
FORCEPROP 2 LAST PATH I182
J 0
(8025 1525);
DISPLAY 1.021277 (8025 1525);
PAINT ORANGE (8025 1525);
DISPLAY INVISIBLE (8025 1525);
FORCEPROP 1 LAST COMMENT_BODY TRUE
J 0
(8075 1375);
DISPLAY 1.170213 (8075 1375);
PAINT GREEN (8075 1375);
DISPLAY INVISIBLE (8075 1375);
FORCEPROP 2 LAST CDS_LIB mstr_standard
J 0
(7975 1450);
PAINT ORANGE (7975 1450);
DISPLAY INVISIBLE (7975 1450);
FORCEADD OFFPAGE..6
(7975 1400);
FORCEPROP 2 LAST $XR1 112 
J 0
(7606 1400);
DISPLAY 0.638298 (7606 1400);
PAINT MONO (7606 1400);
FORCEPROP 2 LAST $XR0 21 
J 0
(7726 1400);
DISPLAY 0.638298 (7726 1400);
PAINT MONO (7726 1400);
FORCEPROP 1 LAST OFFPAGE TRUE
J 0
(8300 1275);
DISPLAY 1.170213 (8300 1275);
PAINT GREEN (8300 1275);
DISPLAY INVISIBLE (8300 1275);
FORCEPROP 1 LAST COMMENT_BODY TRUE
J 0
(8075 1325);
DISPLAY 1.170213 (8075 1325);
PAINT GREEN (8075 1325);
DISPLAY INVISIBLE (8075 1325);
FORCEPROP 2 LAST PATH I183
J 0
(8025 1475);
DISPLAY 1.021277 (8025 1475);
PAINT ORANGE (8025 1475);
DISPLAY INVISIBLE (8025 1475);
FORCEPROP 2 LAST CDS_LIB mstr_standard
J 0
(7975 1400);
PAINT ORANGE (7975 1400);
DISPLAY INVISIBLE (7975 1400);
FORCEADD OFFPAGE..4
(12550 1050);
FORCEPROP 2 LAST $XR1 21 
J 0
(12856 1050);
DISPLAY 0.638298 (12856 1050);
PAINT MONO (12856 1050);
FORCEPROP 2 LAST $XR0 112 
J 0
(12736 1050);
DISPLAY 0.638298 (12736 1050);
PAINT MONO (12736 1050);
FORCEPROP 2 LAST PATH I184
J 0
(12725 1125);
DISPLAY 1.021277 (12725 1125);
PAINT ORANGE (12725 1125);
DISPLAY INVISIBLE (12725 1125);
FORCEPROP 2 LAST CDS_LIB mstr_standard
J 0
(12550 1050);
PAINT ORANGE (12550 1050);
DISPLAY INVISIBLE (12550 1050);
FORCEPROP 1 LAST OFFPAGE TRUE
J 0
(12875 925);
DISPLAY 1.170213 (12875 925);
PAINT GREEN (12875 925);
DISPLAY INVISIBLE (12875 925);
FORCEPROP 1 LAST COMMENT_BODY TRUE
J 0
(12525 950);
DISPLAY 1.170213 (12525 950);
PAINT GREEN (12525 950);
DISPLAY INVISIBLE (12525 950);
FORCEADD OFFPAGE..2
(12550 1000);
FORCEPROP 2 LAST $XR1 112 
J 0
(12829 1000);
DISPLAY 0.638298 (12829 1000);
PAINT MONO (12829 1000);
FORCEPROP 2 LAST $XR0 21 
J 0
(12739 1000);
DISPLAY 0.638298 (12739 1000);
PAINT MONO (12739 1000);
FORCEPROP 2 LAST PATH I185
J 0
(12725 1075);
DISPLAY 1.021277 (12725 1075);
PAINT ORANGE (12725 1075);
DISPLAY INVISIBLE (12725 1075);
FORCEPROP 2 LAST CDS_LIB mstr_standard
J 0
(12550 1000);
PAINT ORANGE (12550 1000);
DISPLAY INVISIBLE (12550 1000);
FORCEPROP 1 LAST OFFPAGE TRUE
J 0
(12875 875);
DISPLAY 1.170213 (12875 875);
PAINT GREEN (12875 875);
DISPLAY INVISIBLE (12875 875);
FORCEPROP 1 LAST COMMENT_BODY TRUE
J 0
(12505 905);
DISPLAY 1.170213 (12505 905);
PAINT GREEN (12505 905);
DISPLAY INVISIBLE (12505 905);
FORCEADD OFFPAGE..1
(8000 2150);
FORCEPROP 2 LAST $XR0 156 
J 0
(7748 2150);
DISPLAY 0.638298 (7748 2150);
PAINT MONO (7748 2150);
FORCEPROP 1 LAST OFFPAGE TRUE
J 0
(8325 2025);
DISPLAY 0.872340 (8325 2025);
PAINT GREEN (8325 2025);
DISPLAY INVISIBLE (8325 2025);
FORCEPROP 1 LAST COMMENT_BODY TRUE
J 0
(8125 2050);
DISPLAY 0.872340 (8125 2050);
PAINT GREEN (8125 2050);
DISPLAY INVISIBLE (8125 2050);
FORCEPROP 2 LAST PATH I186
J 0
(8050 2225);
DISPLAY 1.021277 (8050 2225);
PAINT ORANGE (8050 2225);
DISPLAY INVISIBLE (8050 2225);
FORCEPROP 2 LAST CDS_LIB mstr_standard
J 0
(8000 2150);
PAINT ORANGE (8000 2150);
DISPLAY INVISIBLE (8000 2150);
FORCEADD OFFPAGE..6
(8000 2100);
FORCEPROP 1 LAST OFFPAGE TRUE
J 0
(8325 1975);
DISPLAY 0.872340 (8325 1975);
PAINT GREEN (8325 1975);
DISPLAY INVISIBLE (8325 1975);
FORCEPROP 2 LAST PATH I187
J 0
(8050 2175);
DISPLAY 1.021277 (8050 2175);
PAINT ORANGE (8050 2175);
DISPLAY INVISIBLE (8050 2175);
FORCEPROP 2 LAST CDS_LIB mstr_standard
J 0
(8000 2100);
PAINT ORANGE (8000 2100);
DISPLAY INVISIBLE (8000 2100);
FORCEPROP 1 LAST COMMENT_BODY TRUE
J 0
(8100 2025);
DISPLAY 0.872340 (8100 2025);
PAINT GREEN (8100 2025);
DISPLAY INVISIBLE (8100 2025);
FORCEPROP 2 LAST $XR0 156 
J 0
(7546 2100);
DISPLAY 0.638298 (7546 2100);
PAINT MONO (7546 2100);
DISPLAY INVISIBLE (7546 2100);
FORCEADD OFFPAGE..4
(12525 1700);
FORCEPROP 2 LAST $XR0 156 
J 0
(12711 1700);
DISPLAY 0.638298 (12711 1700);
PAINT MONO (12711 1700);
FORCEPROP 1 LAST OFFPAGE TRUE
J 0
(12850 1575);
DISPLAY 0.872340 (12850 1575);
PAINT GREEN (12850 1575);
DISPLAY INVISIBLE (12850 1575);
FORCEPROP 2 LAST PATH I188
J 0
(12575 1775);
DISPLAY 1.021277 (12575 1775);
PAINT ORANGE (12575 1775);
DISPLAY INVISIBLE (12575 1775);
FORCEPROP 2 LAST CDS_LIB mstr_standard
J 0
(12525 1700);
PAINT ORANGE (12525 1700);
DISPLAY INVISIBLE (12525 1700);
FORCEPROP 1 LAST COMMENT_BODY TRUE
J 0
(12500 1600);
DISPLAY 0.872340 (12500 1600);
PAINT GREEN (12500 1600);
DISPLAY INVISIBLE (12500 1600);
FORCEADD OFFPAGE..4
(12525 1450);
FORCEPROP 2 LAST $XR0 156 
J 0
(12711 1450);
DISPLAY 0.638298 (12711 1450);
PAINT MONO (12711 1450);
FORCEPROP 1 LAST OFFPAGE TRUE
J 0
(12850 1325);
DISPLAY 0.872340 (12850 1325);
PAINT GREEN (12850 1325);
DISPLAY INVISIBLE (12850 1325);
FORCEPROP 2 LAST PATH I189
J 0
(12700 1525);
DISPLAY 1.021277 (12700 1525);
PAINT ORANGE (12700 1525);
DISPLAY INVISIBLE (12700 1525);
FORCEPROP 2 LAST CDS_LIB mstr_standard
J 0
(12525 1450);
PAINT ORANGE (12525 1450);
DISPLAY INVISIBLE (12525 1450);
FORCEPROP 1 LAST COMMENT_BODY TRUE
J 0
(12500 1350);
DISPLAY 0.872340 (12500 1350);
PAINT GREEN (12500 1350);
DISPLAY INVISIBLE (12500 1350);
FORCEADD RES..2
(13600 3200);
FORCEPROP 1 LASTPIN (13600 3100) $PN 2
J 0
(13605 3110);
DISPLAY 0.617021 (13605 3110);
PAINT GREEN (13605 3110);
FORCEPROP 1 LASTPIN (13600 3300) $PN 1
J 0
(13605 3262);
DISPLAY 0.617021 (13605 3262);
PAINT GREEN (13605 3262);
FORCEPROP 1 LAST PART_NUMBER G21796-047
J 0
(13640 3075);
DISPLAY 0.617021 (13640 3075);
PAINT BLUE (13640 3075);
FORCEPROP 1 LAST LOCATION R3B2
J 0
(13645 3325);
DISPLAY 0.617021 (13645 3325);
PAINT AQUA (13645 3325);
FORCEPROP 1 LAST VALUE 49.9
J 0
(13645 3275);
DISPLAY 0.617021 (13645 3275);
PAINT SKYBLUE (13645 3275);
FORCEPROP 1 LAST PACK_TYPE 0402
J 0
(13640 3025);
DISPLAY 0.638298 (13640 3025);
PAINT SKYBLUE (13640 3025);
FORCEPROP 1 LAST TOLERANCE 1%
J 0
(13645 3225);
DISPLAY 0.638298 (13645 3225);
PAINT SKYBLUE (13645 3225);
FORCEPROP 1 LAST WATTAGE 1/16W
J 0
(13640 3175);
DISPLAY 0.638298 (13640 3175);
PAINT SKYBLUE (13640 3175);
FORCEPROP 1 LAST MATERIAL CHIP
J 0
(13640 3125);
DISPLAY 0.617021 (13640 3125);
PAINT SKYBLUE (13640 3125);
FORCEPROP 2 LAST CDS_LIB mstr_discrete
J 0
(13600 3200);
PAINT ORANGE (13600 3200);
DISPLAY INVISIBLE (13600 3200);
FORCEPROP 2 LAST SEC_TYPE 0402
J 0
(13650 3425);
DISPLAY 1.021277 (13650 3425);
PAINT ORANGE (13650 3425);
DISPLAY INVISIBLE (13650 3425);
FORCEPROP 2 LAST BOM_COST PROC_SOCKET
J 0
(13650 3425);
PAINT MONO (13650 3425);
DISPLAY INVISIBLE (13650 3425);
FORCEPROP 2 LAST SEC 1
J 0
(13650 3425);
DISPLAY 0.680851 (13650 3425);
PAINT MONO (13650 3425);
DISPLAY INVISIBLE (13650 3425);
FORCEPROP 2 LAST CDS_LOCATION R3B2
J 0
(13645 3325);
DISPLAY 0.617021 (13645 3325);
PAINT AQUA (13645 3325);
DISPLAY INVISIBLE (13645 3325);
FORCEPROP 1 LAST PATH I19
J 0
(13650 3375);
DISPLAY 0.978723 (13650 3375);
PAINT WHITE (13650 3375);
DISPLAY INVISIBLE (13650 3375);
FORCEPROP 2 LAST ROOM CPU1
J 0
(13650 3375);
PAINT MONO (13650 3375);
DISPLAY INVISIBLE (13650 3375);
FORCEADD OFFPAGE..4
(12525 1400);
FORCEPROP 2 LAST $XR0 156 
J 0
(12711 1400);
DISPLAY 0.638298 (12711 1400);
PAINT MONO (12711 1400);
FORCEPROP 1 LAST OFFPAGE TRUE
J 0
(12850 1275);
DISPLAY 0.872340 (12850 1275);
PAINT GREEN (12850 1275);
DISPLAY INVISIBLE (12850 1275);
FORCEPROP 2 LAST PATH I190
J 0
(12700 1475);
DISPLAY 1.021277 (12700 1475);
PAINT ORANGE (12700 1475);
DISPLAY INVISIBLE (12700 1475);
FORCEPROP 2 LAST CDS_LIB mstr_standard
J 0
(12525 1400);
PAINT ORANGE (12525 1400);
DISPLAY INVISIBLE (12525 1400);
FORCEPROP 1 LAST COMMENT_BODY TRUE
J 0
(12500 1300);
DISPLAY 0.872340 (12500 1300);
PAINT GREEN (12500 1300);
DISPLAY INVISIBLE (12500 1300);
FORCEADD OFFPAGE..4
(12525 1350);
FORCEPROP 2 LAST $XR0 156 
J 0
(12711 1350);
DISPLAY 0.638298 (12711 1350);
PAINT MONO (12711 1350);
FORCEPROP 1 LAST OFFPAGE TRUE
J 0
(12850 1225);
DISPLAY 0.872340 (12850 1225);
PAINT GREEN (12850 1225);
DISPLAY INVISIBLE (12850 1225);
FORCEPROP 2 LAST PATH I191
J 0
(12700 1425);
DISPLAY 1.021277 (12700 1425);
PAINT ORANGE (12700 1425);
DISPLAY INVISIBLE (12700 1425);
FORCEPROP 2 LAST CDS_LIB mstr_standard
J 0
(12525 1350);
PAINT ORANGE (12525 1350);
DISPLAY INVISIBLE (12525 1350);
FORCEPROP 1 LAST COMMENT_BODY TRUE
J 0
(12500 1250);
DISPLAY 0.872340 (12500 1250);
PAINT GREEN (12500 1250);
DISPLAY INVISIBLE (12500 1250);
FORCEADD OFFPAGE..6
(7975 1150);
FORCEPROP 2 LAST $XR1 112 
J 0
(7606 1150);
DISPLAY 0.638298 (7606 1150);
PAINT MONO (7606 1150);
FORCEPROP 2 LAST $XR0 21 
J 0
(7726 1150);
DISPLAY 0.638298 (7726 1150);
PAINT MONO (7726 1150);
FORCEPROP 1 LAST OFFPAGE TRUE
J 0
(8300 1025);
DISPLAY 1.170213 (8300 1025);
PAINT GREEN (8300 1025);
DISPLAY INVISIBLE (8300 1025);
FORCEPROP 1 LAST COMMENT_BODY TRUE
J 0
(8075 1075);
DISPLAY 1.170213 (8075 1075);
PAINT GREEN (8075 1075);
DISPLAY INVISIBLE (8075 1075);
FORCEPROP 2 LAST PATH I2
J 0
(8025 1225);
DISPLAY 1.021277 (8025 1225);
PAINT ORANGE (8025 1225);
DISPLAY INVISIBLE (8025 1225);
FORCEPROP 2 LAST CDS_LIB mstr_standard
J 0
(7975 1150);
PAINT MONO (7975 1150);
DISPLAY INVISIBLE (7975 1150);
FORCEADD RES..2
(13325 3200);
FORCEPROP 1 LAST LOCATION R3B4
J 0
(13370 3325);
DISPLAY 0.617021 (13370 3325);
PAINT AQUA (13370 3325);
FORCEPROP 1 LASTPIN (13325 3300) $PN 1
J 0
(13330 3262);
DISPLAY 0.617021 (13330 3262);
PAINT GREEN (13330 3262);
FORCEPROP 1 LASTPIN (13325 3100) $PN 2
J 0
(13330 3110);
DISPLAY 0.617021 (13330 3110);
PAINT GREEN (13330 3110);
FORCEPROP 1 LAST VALUE 100.0
J 0
(13370 3275);
DISPLAY 0.617021 (13370 3275);
PAINT SKYBLUE (13370 3275);
FORCEPROP 1 LAST MATERIAL CHIP
J 0
(13365 3125);
DISPLAY 0.617021 (13365 3125);
PAINT SKYBLUE (13365 3125);
FORCEPROP 1 LAST TOLERANCE 1%
J 0
(13370 3225);
DISPLAY 0.638298 (13370 3225);
PAINT SKYBLUE (13370 3225);
FORCEPROP 1 LAST WATTAGE 1/16W
J 0
(13365 3175);
DISPLAY 0.638298 (13365 3175);
PAINT SKYBLUE (13365 3175);
FORCEPROP 1 LAST PACK_TYPE 0402
J 0
(13365 3025);
DISPLAY 0.638298 (13365 3025);
PAINT SKYBLUE (13365 3025);
FORCEPROP 1 LAST PART_NUMBER G21796-017
J 0
(13365 3075);
DISPLAY 0.617021 (13365 3075);
PAINT BLUE (13365 3075);
FORCEPROP 2 LAST SEC 1
J 0
(13375 3425);
DISPLAY 0.680851 (13375 3425);
PAINT MONO (13375 3425);
DISPLAY INVISIBLE (13375 3425);
FORCEPROP 2 LAST CDS_LOCATION R3B4
J 0
(13370 3325);
DISPLAY 0.617021 (13370 3325);
PAINT AQUA (13370 3325);
DISPLAY INVISIBLE (13370 3325);
FORCEPROP 1 LAST PATH I21
J 0
(13375 3375);
DISPLAY 0.978723 (13375 3375);
PAINT WHITE (13375 3375);
DISPLAY INVISIBLE (13375 3375);
FORCEPROP 2 LAST ROOM CPU1
J 0
(13375 3375);
PAINT MONO (13375 3375);
DISPLAY INVISIBLE (13375 3375);
FORCEPROP 2 LAST BOM_COST PROC_SOCKET
J 0
(13375 3425);
PAINT MONO (13375 3425);
DISPLAY INVISIBLE (13375 3425);
FORCEPROP 2 LAST SEC_TYPE 0402
J 0
(13375 3425);
DISPLAY 1.021277 (13375 3425);
PAINT ORANGE (13375 3425);
DISPLAY INVISIBLE (13375 3425);
FORCEPROP 2 LAST CDS_LIB mstr_discrete
J 0
(13325 3200);
PAINT ORANGE (13325 3200);
DISPLAY INVISIBLE (13325 3200);
FORCEADD PVCCIO_CPU1..1
(13950 2975);
FORCEPROP 3 LASTPIN (13950 2925) SIG_NAME PVCCIO_CPU1\g
J 0
(13960 2935);
DISPLAY 0.659574 (13960 2935);
PAINT MONO (13960 2935);
DISPLAY INVISIBLE (13960 2935);
FORCEPROP 1 LAST BODY_TYPE PLUMBING
J 0
(13905 2932);
DISPLAY 0.340426 (13905 2932);
PAINT GREEN (13905 2932);
DISPLAY INVISIBLE (13905 2932);
FORCEPROP 1 LAST VOLTAGE 1.1V
J 0
(13905 2932);
DISPLAY 0.340426 (13905 2932);
PAINT SKYBLUE (13905 2932);
DISPLAY INVISIBLE (13905 2932);
FORCEPROP 2 LAST CDS_LIB mstr_symbols
J 0
(13950 2975);
PAINT ORANGE (13950 2975);
DISPLAY INVISIBLE (13950 2975);
FORCEPROP 1 LAST PATH I22
J 0
(14000 3000);
DISPLAY 0.872340 (14000 3000);
PAINT AQUA (14000 3000);
DISPLAY INVISIBLE (14000 3000);
FORCEPROP 1 LAST HDL_POWER PVCCIO_CPU1
J 1
(13950 3025);
DISPLAY 0.872340 (13950 3025);
PAINT GREEN (13950 3025);
DISPLAY INVISIBLE (13950 3025);
FORCEADD OFFPAGE..3
(12775 3750);
FORCEPROP 2 LAST $XR1 166 
J 0
(13079 3750);
DISPLAY 0.638298 (13079 3750);
PAINT MONO (13079 3750);
FORCEPROP 2 LAST $XR0 21 
J 0
(12989 3750);
DISPLAY 0.638298 (12989 3750);
PAINT MONO (12989 3750);
FORCEPROP 2 LAST PATH I23
J 0
(13325 3800);
DISPLAY 1.021277 (13325 3800);
PAINT ORANGE (13325 3800);
DISPLAY INVISIBLE (13325 3800);
FORCEPROP 1 LAST OFFPAGE TRUE
J 0
(13100 3625);
DISPLAY 1.170213 (13100 3625);
PAINT GREEN (13100 3625);
DISPLAY INVISIBLE (13100 3625);
FORCEPROP 1 LAST COMMENT_BODY TRUE
J 0
(12725 3650);
DISPLAY 1.170213 (12725 3650);
PAINT GREEN (12725 3650);
DISPLAY INVISIBLE (12725 3650);
FORCEPROP 2 LAST CDS_LIB mstr_standard
J 0
(12775 3750);
PAINT MONO (12775 3750);
DISPLAY INVISIBLE (12775 3750);
FORCEADD RES..1
(12250 3650);
FORCEPROP 1 LAST PART_NUMBER G21497-005
J 0
(11925 3650);
DISPLAY 0.617021 (11925 3650);
PAINT BLUE (11925 3650);
FORCEPROP 1 LASTPIN (12150 3650) $PN 1
J 0
(12162 3662);
DISPLAY 0.617021 (12162 3662);
PAINT GREEN (12162 3662);
FORCEPROP 1 LAST LOCATION R1C2
J 0
(11800 3650);
DISPLAY 0.617021 (11800 3650);
PAINT AQUA (11800 3650);
FORCEPROP 1 LASTPIN (12350 3650) $PN 2
J 0
(12312 3662);
DISPLAY 0.617021 (12312 3662);
PAINT GREEN (12312 3662);
FORCEPROP 1 LAST TOLERANCE 5%
J 0
(12475 3650);
DISPLAY 0.617021 (12475 3650);
PAINT SKYBLUE (12475 3650);
FORCEPROP 1 LAST VALUE 0.0
J 0
(12375 3650);
DISPLAY 0.617021 (12375 3650);
PAINT SKYBLUE (12375 3650);
FORCEPROP 1 LAST WATTAGE 1/16W
J 0
(12700 3650);
DISPLAY 0.553191 (12700 3650);
PAINT SKYBLUE (12700 3650);
FORCEPROP 1 LAST PACK_TYPE 0402
J 0
(12600 3650);
DISPLAY 0.617021 (12600 3650);
PAINT SKYBLUE (12600 3650);
FORCEPROP 2 LAST CDS_LOCATION R1C2
J 0
(11775 3625);
DISPLAY 0.617021 (11775 3625);
PAINT AQUA (11775 3625);
DISPLAY INVISIBLE (11775 3625);
FORCEPROP 1 LAST PATH I24
J 0
(12200 3800);
DISPLAY 0.978723 (12200 3800);
PAINT WHITE (12200 3800);
DISPLAY INVISIBLE (12200 3800);
FORCEPROP 2 LAST CDS_SEC 1
J 0
(12200 3850);
DISPLAY 1.340426 (12200 3850);
PAINT MONO (12200 3850);
DISPLAY INVISIBLE (12200 3850);
FORCEPROP 2 LAST $SEC 1
J 0
(12200 3850);
DISPLAY 1.340426 (12200 3850);
PAINT MONO (12200 3850);
DISPLAY INVISIBLE (12200 3850);
FORCEPROP 1 LAST MATERIAL CHIP
J 0
(12400 3550);
PAINT SKYBLUE (12400 3550);
DISPLAY INVISIBLE (12400 3550);
FORCEPROP 2 LAST CDS_LIB mstr_discrete
J 0
(12250 3650);
DISPLAY 1.340426 (12250 3650);
PAINT ORANGE (12250 3650);
DISPLAY INVISIBLE (12250 3650);
FORCEPROP 2 LAST BOM_COST PROC_SOCKET
J 0
(12550 3725);
PAINT MONO (12550 3725);
DISPLAY INVISIBLE (12550 3725);
FORCEPROP 2 LAST ROOM CPU1
J 0
(12550 3675);
PAINT MONO (12550 3675);
DISPLAY INVISIBLE (12550 3675);
FORCEADD RES..1
(12250 3600);
FORCEPROP 1 LAST PART_NUMBER G21497-005
J 0
(11925 3600);
DISPLAY 0.617021 (11925 3600);
PAINT BLUE (11925 3600);
FORCEPROP 1 LASTPIN (12150 3600) $PN 1
J 0
(12162 3612);
DISPLAY 0.617021 (12162 3612);
PAINT GREEN (12162 3612);
FORCEPROP 1 LASTPIN (12350 3600) $PN 2
J 0
(12312 3612);
DISPLAY 0.617021 (12312 3612);
PAINT GREEN (12312 3612);
FORCEPROP 1 LAST TOLERANCE 5%
J 0
(12475 3600);
DISPLAY 0.617021 (12475 3600);
PAINT SKYBLUE (12475 3600);
FORCEPROP 1 LAST LOCATION R1C3
J 0
(11800 3600);
DISPLAY 0.617021 (11800 3600);
PAINT AQUA (11800 3600);
FORCEPROP 1 LAST VALUE 0.0
J 0
(12375 3600);
DISPLAY 0.617021 (12375 3600);
PAINT SKYBLUE (12375 3600);
FORCEPROP 1 LAST PACK_TYPE 0402
J 0
(12600 3600);
DISPLAY 0.617021 (12600 3600);
PAINT SKYBLUE (12600 3600);
FORCEPROP 1 LAST WATTAGE 1/16W
J 0
(12700 3600);
DISPLAY 0.553191 (12700 3600);
PAINT SKYBLUE (12700 3600);
FORCEPROP 2 LAST CDS_LOCATION R1C3
J 0
(11775 3575);
DISPLAY 0.617021 (11775 3575);
PAINT AQUA (11775 3575);
DISPLAY INVISIBLE (11775 3575);
FORCEPROP 1 LAST PATH I25
J 0
(12200 3750);
DISPLAY 0.978723 (12200 3750);
PAINT WHITE (12200 3750);
DISPLAY INVISIBLE (12200 3750);
FORCEPROP 2 LAST CDS_SEC 1
J 0
(12200 3800);
DISPLAY 1.340426 (12200 3800);
PAINT MONO (12200 3800);
DISPLAY INVISIBLE (12200 3800);
FORCEPROP 2 LAST $SEC 1
J 0
(12200 3800);
DISPLAY 1.340426 (12200 3800);
PAINT MONO (12200 3800);
DISPLAY INVISIBLE (12200 3800);
FORCEPROP 1 LAST MATERIAL CHIP
J 0
(12400 3500);
PAINT SKYBLUE (12400 3500);
DISPLAY INVISIBLE (12400 3500);
FORCEPROP 2 LAST CDS_LIB mstr_discrete
J 0
(12250 3600);
DISPLAY 1.340426 (12250 3600);
PAINT ORANGE (12250 3600);
DISPLAY INVISIBLE (12250 3600);
FORCEPROP 2 LAST ROOM CPU1
J 0
(12550 3625);
PAINT MONO (12550 3625);
DISPLAY INVISIBLE (12550 3625);
FORCEPROP 2 LAST BOM_COST PROC_SOCKET
J 0
(12550 3675);
PAINT MONO (12550 3675);
DISPLAY INVISIBLE (12550 3675);
FORCEADD RES..1
(12250 3550);
FORCEPROP 1 LAST PART_NUMBER G21796-271
J 0
(11925 3550);
DISPLAY 0.617021 (11925 3550);
PAINT BLUE (11925 3550);
FORCEPROP 1 LASTPIN (12150 3550) $PN 1
J 0
(12162 3562);
DISPLAY 0.617021 (12162 3562);
PAINT GREEN (12162 3562);
FORCEPROP 1 LAST LOCATION R1C1
J 0
(11800 3550);
DISPLAY 0.617021 (11800 3550);
PAINT AQUA (11800 3550);
FORCEPROP 1 LASTPIN (12350 3550) $PN 2
J 0
(12312 3562);
DISPLAY 0.617021 (12312 3562);
PAINT GREEN (12312 3562);
FORCEPROP 1 LAST PACK_TYPE 0402
J 0
(12600 3550);
DISPLAY 0.617021 (12600 3550);
PAINT SKYBLUE (12600 3550);
FORCEPROP 1 LAST TOLERANCE 1.0%
J 0
(12475 3550);
DISPLAY 0.617021 (12475 3550);
PAINT SKYBLUE (12475 3550);
FORCEPROP 1 LAST VALUE 221
J 0
(12375 3550);
DISPLAY 0.617021 (12375 3550);
PAINT SKYBLUE (12375 3550);
FORCEPROP 1 LAST WATTAGE 1/16W
J 0
(12700 3550);
DISPLAY 0.553191 (12700 3550);
PAINT SKYBLUE (12700 3550);
FORCEPROP 2 LAST CDS_LOCATION R1C1
J 0
(11775 3525);
DISPLAY 0.617021 (11775 3525);
PAINT AQUA (11775 3525);
DISPLAY INVISIBLE (11775 3525);
FORCEPROP 1 LAST PATH I26
J 0
(12200 3700);
DISPLAY 0.978723 (12200 3700);
PAINT WHITE (12200 3700);
DISPLAY INVISIBLE (12200 3700);
FORCEPROP 2 LAST $SEC 1
J 0
(12200 3750);
DISPLAY 1.340426 (12200 3750);
PAINT MONO (12200 3750);
DISPLAY INVISIBLE (12200 3750);
FORCEPROP 2 LAST CDS_SEC 1
J 0
(12200 3750);
DISPLAY 1.340426 (12200 3750);
PAINT MONO (12200 3750);
DISPLAY INVISIBLE (12200 3750);
FORCEPROP 1 LAST MATERIAL CHIP
J 0
(12400 3450);
PAINT SKYBLUE (12400 3450);
DISPLAY INVISIBLE (12400 3450);
FORCEPROP 2 LAST ROOM CPU1
J 0
(12550 3575);
PAINT MONO (12550 3575);
DISPLAY INVISIBLE (12550 3575);
FORCEPROP 2 LAST CDS_LIB mstr_discrete
J 0
(12250 3550);
DISPLAY 1.340426 (12250 3550);
PAINT ORANGE (12250 3550);
DISPLAY INVISIBLE (12250 3550);
FORCEPROP 2 LAST BOM_COST PROC_SOCKET
J 0
(12550 3625);
PAINT MONO (12550 3625);
DISPLAY INVISIBLE (12550 3625);
FORCEADD RES..1
(12250 3400);
FORCEPROP 1 LASTPIN (12150 3400) $PN 1
J 0
(12162 3412);
DISPLAY 0.617021 (12162 3412);
PAINT GREEN (12162 3412);
FORCEPROP 1 LAST PART_NUMBER G21796-271
J 0
(11925 3400);
DISPLAY 0.617021 (11925 3400);
PAINT BLUE (11925 3400);
FORCEPROP 1 LAST LOCATION R3B1
J 0
(11800 3400);
DISPLAY 0.617021 (11800 3400);
PAINT AQUA (11800 3400);
FORCEPROP 1 LAST VALUE 221
J 0
(12375 3400);
DISPLAY 0.617021 (12375 3400);
PAINT SKYBLUE (12375 3400);
FORCEPROP 1 LASTPIN (12350 3400) $PN 2
J 0
(12312 3412);
DISPLAY 0.617021 (12312 3412);
PAINT GREEN (12312 3412);
FORCEPROP 1 LAST PACK_TYPE 0402
J 0
(12600 3400);
DISPLAY 0.617021 (12600 3400);
PAINT SKYBLUE (12600 3400);
FORCEPROP 1 LAST TOLERANCE 1.0%
J 0
(12475 3400);
DISPLAY 0.617021 (12475 3400);
PAINT SKYBLUE (12475 3400);
FORCEPROP 1 LAST WATTAGE 1/16W
J 0
(12700 3400);
DISPLAY 0.553191 (12700 3400);
PAINT SKYBLUE (12700 3400);
FORCEPROP 2 LAST CDS_LOCATION R3B1
J 0
(11775 3375);
DISPLAY 0.617021 (11775 3375);
PAINT AQUA (11775 3375);
DISPLAY INVISIBLE (11775 3375);
FORCEPROP 1 LAST PATH I27
J 0
(12200 3550);
DISPLAY 0.978723 (12200 3550);
PAINT WHITE (12200 3550);
DISPLAY INVISIBLE (12200 3550);
FORCEPROP 2 LAST CDS_SEC 1
J 0
(12200 3600);
DISPLAY 1.340426 (12200 3600);
PAINT MONO (12200 3600);
DISPLAY INVISIBLE (12200 3600);
FORCEPROP 2 LAST $SEC 1
J 0
(12200 3600);
DISPLAY 1.340426 (12200 3600);
PAINT MONO (12200 3600);
DISPLAY INVISIBLE (12200 3600);
FORCEPROP 1 LAST MATERIAL CHIP
J 0
(12400 3300);
PAINT SKYBLUE (12400 3300);
DISPLAY INVISIBLE (12400 3300);
FORCEPROP 2 LAST CDS_LIB mstr_discrete
J 0
(12250 3400);
DISPLAY 1.340426 (12250 3400);
PAINT ORANGE (12250 3400);
DISPLAY INVISIBLE (12250 3400);
FORCEPROP 2 LAST ROOM CPU1
J 0
(12550 3425);
PAINT MONO (12550 3425);
DISPLAY INVISIBLE (12550 3425);
FORCEPROP 2 LAST BOM_COST PROC_SOCKET
J 0
(12550 3475);
PAINT MONO (12550 3475);
DISPLAY INVISIBLE (12550 3475);
FORCEADD RES..1
(12250 3450);
FORCEPROP 1 LAST LOCATION R3B5
J 0
(11800 3450);
DISPLAY 0.617021 (11800 3450);
PAINT AQUA (11800 3450);
FORCEPROP 1 LASTPIN (12150 3450) $PN 1
J 0
(12162 3462);
DISPLAY 0.617021 (12162 3462);
PAINT GREEN (12162 3462);
FORCEPROP 1 LAST PART_NUMBER G21497-005
J 0
(11925 3450);
DISPLAY 0.617021 (11925 3450);
PAINT BLUE (11925 3450);
FORCEPROP 1 LASTPIN (12350 3450) $PN 2
J 0
(12312 3462);
DISPLAY 0.617021 (12312 3462);
PAINT GREEN (12312 3462);
FORCEPROP 1 LAST PACK_TYPE 0402
J 0
(12600 3450);
DISPLAY 0.617021 (12600 3450);
PAINT SKYBLUE (12600 3450);
FORCEPROP 1 LAST VALUE 0.0
J 0
(12375 3450);
DISPLAY 0.617021 (12375 3450);
PAINT SKYBLUE (12375 3450);
FORCEPROP 1 LAST TOLERANCE 5%
J 0
(12475 3450);
DISPLAY 0.617021 (12475 3450);
PAINT SKYBLUE (12475 3450);
FORCEPROP 1 LAST WATTAGE 1/16W
J 0
(12700 3450);
DISPLAY 0.553191 (12700 3450);
PAINT SKYBLUE (12700 3450);
FORCEPROP 2 LAST CDS_LOCATION R3B5
J 0
(11775 3425);
DISPLAY 0.617021 (11775 3425);
PAINT AQUA (11775 3425);
DISPLAY INVISIBLE (11775 3425);
FORCEPROP 2 LAST CDS_SEC 1
J 0
(12200 3650);
DISPLAY 1.340426 (12200 3650);
PAINT MONO (12200 3650);
DISPLAY INVISIBLE (12200 3650);
FORCEPROP 2 LAST $SEC 1
J 0
(12200 3650);
DISPLAY 1.340426 (12200 3650);
PAINT MONO (12200 3650);
DISPLAY INVISIBLE (12200 3650);
FORCEPROP 1 LAST PATH I28
J 0
(12200 3600);
DISPLAY 0.978723 (12200 3600);
PAINT WHITE (12200 3600);
DISPLAY INVISIBLE (12200 3600);
FORCEPROP 2 LAST CDS_LIB mstr_discrete
J 0
(12250 3450);
DISPLAY 1.340426 (12250 3450);
PAINT ORANGE (12250 3450);
DISPLAY INVISIBLE (12250 3450);
FORCEPROP 1 LAST MATERIAL CHIP
J 0
(12400 3350);
PAINT SKYBLUE (12400 3350);
DISPLAY INVISIBLE (12400 3350);
FORCEPROP 2 LAST ROOM CPU1
J 0
(12550 3475);
PAINT MONO (12550 3475);
DISPLAY INVISIBLE (12550 3475);
FORCEPROP 2 LAST BOM_COST PROC_SOCKET
J 0
(12550 3525);
PAINT MONO (12550 3525);
DISPLAY INVISIBLE (12550 3525);
FORCEADD RES..1
(12250 3500);
FORCEPROP 1 LAST PART_NUMBER G21497-005
J 0
(11925 3500);
DISPLAY 0.617021 (11925 3500);
PAINT BLUE (11925 3500);
FORCEPROP 1 LASTPIN (12150 3500) $PN 1
J 0
(12162 3512);
DISPLAY 0.617021 (12162 3512);
PAINT GREEN (12162 3512);
FORCEPROP 1 LAST LOCATION R3B3
J 0
(11800 3500);
DISPLAY 0.617021 (11800 3500);
PAINT AQUA (11800 3500);
FORCEPROP 1 LAST VALUE 0.0
J 0
(12375 3500);
DISPLAY 0.617021 (12375 3500);
PAINT SKYBLUE (12375 3500);
FORCEPROP 1 LASTPIN (12350 3500) $PN 2
J 0
(12312 3512);
DISPLAY 0.617021 (12312 3512);
PAINT GREEN (12312 3512);
FORCEPROP 1 LAST PACK_TYPE 0402
J 0
(12600 3500);
DISPLAY 0.617021 (12600 3500);
PAINT SKYBLUE (12600 3500);
FORCEPROP 1 LAST TOLERANCE 5%
J 0
(12475 3500);
DISPLAY 0.617021 (12475 3500);
PAINT SKYBLUE (12475 3500);
FORCEPROP 1 LAST WATTAGE 1/16W
J 0
(12700 3500);
DISPLAY 0.553191 (12700 3500);
PAINT SKYBLUE (12700 3500);
FORCEPROP 2 LAST CDS_LOCATION R3B3
J 0
(11775 3475);
DISPLAY 0.617021 (11775 3475);
PAINT AQUA (11775 3475);
DISPLAY INVISIBLE (11775 3475);
FORCEPROP 1 LAST PATH I29
J 0
(12200 3650);
DISPLAY 0.978723 (12200 3650);
PAINT WHITE (12200 3650);
DISPLAY INVISIBLE (12200 3650);
FORCEPROP 2 LAST $SEC 1
J 0
(12200 3700);
DISPLAY 1.340426 (12200 3700);
PAINT MONO (12200 3700);
DISPLAY INVISIBLE (12200 3700);
FORCEPROP 2 LAST CDS_SEC 1
J 0
(12200 3700);
DISPLAY 1.340426 (12200 3700);
PAINT MONO (12200 3700);
DISPLAY INVISIBLE (12200 3700);
FORCEPROP 2 LAST CDS_LIB mstr_discrete
J 0
(12250 3500);
DISPLAY 1.340426 (12250 3500);
PAINT ORANGE (12250 3500);
DISPLAY INVISIBLE (12250 3500);
FORCEPROP 1 LAST MATERIAL CHIP
J 0
(12400 3400);
PAINT SKYBLUE (12400 3400);
DISPLAY INVISIBLE (12400 3400);
FORCEPROP 2 LAST ROOM CPU1
J 0
(12550 3525);
PAINT MONO (12550 3525);
DISPLAY INVISIBLE (12550 3525);
FORCEPROP 2 LAST BOM_COST PROC_SOCKET
J 0
(12550 3575);
PAINT MONO (12550 3575);
DISPLAY INVISIBLE (12550 3575);
FORCEADD OFFPAGE..6
(7975 1100);
FORCEPROP 2 LAST $XR1 112 
J 0
(7606 1100);
DISPLAY 0.638298 (7606 1100);
PAINT MONO (7606 1100);
FORCEPROP 2 LAST $XR0 21 
J 0
(7726 1100);
DISPLAY 0.638298 (7726 1100);
PAINT MONO (7726 1100);
FORCEPROP 1 LAST OFFPAGE TRUE
J 0
(8300 975);
DISPLAY 1.170213 (8300 975);
PAINT GREEN (8300 975);
DISPLAY INVISIBLE (8300 975);
FORCEPROP 1 LAST COMMENT_BODY TRUE
J 0
(8075 1025);
DISPLAY 1.170213 (8075 1025);
PAINT GREEN (8075 1025);
DISPLAY INVISIBLE (8075 1025);
FORCEPROP 2 LAST PATH I3
J 0
(8025 1175);
DISPLAY 1.021277 (8025 1175);
PAINT ORANGE (8025 1175);
DISPLAY INVISIBLE (8025 1175);
FORCEPROP 2 LAST CDS_LIB mstr_standard
J 0
(7975 1100);
PAINT MONO (7975 1100);
DISPLAY INVISIBLE (7975 1100);
FORCEADD OFFPAGE..3
(12200 3300);
FORCEPROP 2 LAST $XR0 92 
J 0
(12414 3300);
DISPLAY 0.638298 (12414 3300);
PAINT MONO (12414 3300);
FORCEPROP 2 LAST PATH I30
J 0
(12400 3350);
DISPLAY 1.021277 (12400 3350);
PAINT ORANGE (12400 3350);
DISPLAY INVISIBLE (12400 3350);
FORCEPROP 1 LAST OFFPAGE TRUE
J 0
(12525 3175);
DISPLAY 0.872340 (12525 3175);
PAINT GREEN (12525 3175);
DISPLAY INVISIBLE (12525 3175);
FORCEPROP 2 LAST CDS_LIB mstr_standard
J 0
(12200 3300);
PAINT MONO (12200 3300);
DISPLAY INVISIBLE (12200 3300);
FORCEPROP 1 LAST COMMENT_BODY TRUE
J 0
(12150 3200);
DISPLAY 0.872340 (12150 3200);
PAINT GREEN (12150 3200);
DISPLAY INVISIBLE (12150 3200);
FORCEADD OFFPAGE..2
(12225 3200);
FORCEPROP 2 LAST $XR0 92 
J 0
(12414 3200);
DISPLAY 0.638298 (12414 3200);
PAINT MONO (12414 3200);
FORCEPROP 1 LAST OFFPAGE TRUE
J 0
(12550 3075);
DISPLAY 0.872340 (12550 3075);
PAINT GREEN (12550 3075);
DISPLAY INVISIBLE (12550 3075);
FORCEPROP 2 LAST PATH I31
J 0
(12425 3250);
DISPLAY 1.021277 (12425 3250);
PAINT ORANGE (12425 3250);
DISPLAY INVISIBLE (12425 3250);
FORCEPROP 2 LAST CDS_LIB mstr_standard
J 0
(12225 3200);
PAINT MONO (12225 3200);
DISPLAY INVISIBLE (12225 3200);
FORCEPROP 1 LAST COMMENT_BODY TRUE
J 0
(12180 3105);
DISPLAY 0.872340 (12180 3105);
PAINT GREEN (12180 3105);
DISPLAY INVISIBLE (12180 3105);
FORCEADD OFFPAGE..3
(12200 3000);
FORCEPROP 2 LAST $XR0 92 
J 0
(12414 3000);
DISPLAY 0.638298 (12414 3000);
PAINT MONO (12414 3000);
FORCEPROP 2 LAST PATH I32
J 0
(12400 3075);
DISPLAY 1.021277 (12400 3075);
PAINT ORANGE (12400 3075);
DISPLAY INVISIBLE (12400 3075);
FORCEPROP 1 LAST OFFPAGE TRUE
J 0
(12525 2875);
DISPLAY 1.170213 (12525 2875);
PAINT GREEN (12525 2875);
DISPLAY INVISIBLE (12525 2875);
FORCEPROP 2 LAST CDS_LIB mstr_standard
J 0
(12200 3000);
PAINT MONO (12200 3000);
DISPLAY INVISIBLE (12200 3000);
FORCEPROP 1 LAST COMMENT_BODY TRUE
J 0
(12150 2900);
DISPLAY 1.170213 (12150 2900);
PAINT GREEN (12150 2900);
DISPLAY INVISIBLE (12150 2900);
FORCEADD OFFPAGE..2
(12225 3100);
FORCEPROP 2 LAST $XR0 93 
J 0
(12414 3100);
DISPLAY 0.638298 (12414 3100);
PAINT MONO (12414 3100);
FORCEPROP 2 LAST PATH I33
J 0
(12400 3175);
DISPLAY 1.021277 (12400 3175);
PAINT ORANGE (12400 3175);
DISPLAY INVISIBLE (12400 3175);
FORCEPROP 1 LAST OFFPAGE TRUE
J 0
(12550 2975);
DISPLAY 0.872340 (12550 2975);
PAINT GREEN (12550 2975);
DISPLAY INVISIBLE (12550 2975);
FORCEPROP 2 LAST CDS_LIB mstr_standard
J 0
(12225 3100);
PAINT MONO (12225 3100);
DISPLAY INVISIBLE (12225 3100);
FORCEPROP 1 LAST COMMENT_BODY TRUE
J 0
(12180 3005);
DISPLAY 0.872340 (12180 3005);
PAINT GREEN (12180 3005);
DISPLAY INVISIBLE (12180 3005);
FORCEADD OFFPAGE..2
(12225 3150);
FORCEPROP 2 LAST $XR0 93 
J 0
(12414 3150);
DISPLAY 0.638298 (12414 3150);
PAINT MONO (12414 3150);
FORCEPROP 2 LAST PATH I34
J 0
(12400 3225);
DISPLAY 1.021277 (12400 3225);
PAINT ORANGE (12400 3225);
DISPLAY INVISIBLE (12400 3225);
FORCEPROP 1 LAST OFFPAGE TRUE
J 0
(12550 3025);
DISPLAY 0.872340 (12550 3025);
PAINT GREEN (12550 3025);
DISPLAY INVISIBLE (12550 3025);
FORCEPROP 2 LAST CDS_LIB mstr_standard
J 0
(12225 3150);
PAINT MONO (12225 3150);
DISPLAY INVISIBLE (12225 3150);
FORCEPROP 1 LAST COMMENT_BODY TRUE
J 0
(12180 3055);
DISPLAY 0.872340 (12180 3055);
PAINT GREEN (12180 3055);
DISPLAY INVISIBLE (12180 3055);
FORCEADD OFFPAGE..3
(12200 2850);
FORCEPROP 2 LAST $XR1 93 
J 0
(12504 2850);
DISPLAY 0.638298 (12504 2850);
PAINT MONO (12504 2850);
FORCEPROP 2 LAST $XR0 95 
J 0
(12414 2850);
DISPLAY 0.638298 (12414 2850);
PAINT MONO (12414 2850);
FORCEPROP 2 LAST PATH I36
J 0
(12750 2900);
DISPLAY 1.021277 (12750 2900);
PAINT ORANGE (12750 2900);
DISPLAY INVISIBLE (12750 2900);
FORCEPROP 1 LAST OFFPAGE TRUE
J 0
(12525 2725);
DISPLAY 1.170213 (12525 2725);
PAINT GREEN (12525 2725);
DISPLAY INVISIBLE (12525 2725);
FORCEPROP 2 LAST CDS_LIB mstr_standard
J 0
(12200 2850);
PAINT MONO (12200 2850);
DISPLAY INVISIBLE (12200 2850);
FORCEPROP 1 LAST COMMENT_BODY TRUE
J 0
(12150 2750);
DISPLAY 1.170213 (12150 2750);
PAINT GREEN (12150 2750);
DISPLAY INVISIBLE (12150 2750);
FORCEADD OFFPAGE..2
(12225 2800);
FORCEPROP 2 LAST $XR0 92 
J 0
(12414 2800);
DISPLAY 0.638298 (12414 2800);
PAINT MONO (12414 2800);
FORCEPROP 1 LAST OFFPAGE TRUE
J 0
(12550 2675);
DISPLAY 1.170213 (12550 2675);
PAINT GREEN (12550 2675);
DISPLAY INVISIBLE (12550 2675);
FORCEPROP 2 LAST PATH I37
J 0
(12525 2850);
DISPLAY 1.021277 (12525 2850);
PAINT ORANGE (12525 2850);
DISPLAY INVISIBLE (12525 2850);
FORCEPROP 2 LAST CDS_LIB mstr_standard
J 0
(12225 2800);
PAINT MONO (12225 2800);
DISPLAY INVISIBLE (12225 2800);
FORCEPROP 1 LAST COMMENT_BODY TRUE
J 0
(12180 2705);
DISPLAY 1.170213 (12180 2705);
PAINT GREEN (12180 2705);
DISPLAY INVISIBLE (12180 2705);
FORCEADD OFFPAGE..4
(12225 2700);
FORCEPROP 2 LAST $XR0 90 
J 0
(12411 2700);
DISPLAY 0.638298 (12411 2700);
PAINT MONO (12411 2700);
FORCEPROP 1 LAST OFFPAGE TRUE
J 0
(12550 2575);
DISPLAY 1.170213 (12550 2575);
PAINT GREEN (12550 2575);
DISPLAY INVISIBLE (12550 2575);
FORCEPROP 2 LAST PATH I38
J 0
(12400 2775);
DISPLAY 1.021277 (12400 2775);
PAINT ORANGE (12400 2775);
DISPLAY INVISIBLE (12400 2775);
FORCEPROP 2 LAST CDS_LIB mstr_standard
J 0
(12225 2700);
PAINT MONO (12225 2700);
DISPLAY INVISIBLE (12225 2700);
FORCEPROP 1 LAST COMMENT_BODY TRUE
J 0
(12200 2600);
DISPLAY 1.170213 (12200 2600);
PAINT GREEN (12200 2600);
DISPLAY INVISIBLE (12200 2600);
FORCEADD OFFPAGE..4
(12225 2600);
FORCEPROP 2 LAST $XR1 156 
J 0
(12501 2600);
DISPLAY 0.638298 (12501 2600);
PAINT MONO (12501 2600);
FORCEPROP 2 LAST $XR0 90 
J 0
(12411 2600);
DISPLAY 0.638298 (12411 2600);
PAINT MONO (12411 2600);
FORCEPROP 2 LAST PATH I39
J 0
(12425 2650);
DISPLAY 1.021277 (12425 2650);
PAINT ORANGE (12425 2650);
DISPLAY INVISIBLE (12425 2650);
FORCEPROP 1 LAST OFFPAGE TRUE
J 0
(12550 2475);
DISPLAY 1.170213 (12550 2475);
PAINT GREEN (12550 2475);
DISPLAY INVISIBLE (12550 2475);
FORCEPROP 2 LAST CDS_LIB mstr_standard
J 0
(12225 2600);
PAINT MONO (12225 2600);
DISPLAY INVISIBLE (12225 2600);
FORCEPROP 1 LAST COMMENT_BODY TRUE
J 0
(12200 2500);
DISPLAY 1.170213 (12200 2500);
PAINT GREEN (12200 2500);
DISPLAY INVISIBLE (12200 2500);
FORCEADD RES..2
(13600 3925);
FORCEPROP 1 LAST LOCATION R9N1
J 0
(13670 4050);
DISPLAY 0.617021 (13670 4050);
PAINT AQUA (13670 4050);
FORCEPROP 1 LASTPIN (13600 4025) $PN 1
J 0
(13605 3987);
DISPLAY 0.617021 (13605 3987);
PAINT GREEN (13605 3987);
FORCEPROP 1 LAST VALUE 49.9
J 0
(13670 4000);
DISPLAY 0.617021 (13670 4000);
PAINT SKYBLUE (13670 4000);
FORCEPROP 1 LAST WATTAGE 1/16W
J 0
(13665 3900);
DISPLAY 0.638298 (13665 3900);
PAINT SKYBLUE (13665 3900);
FORCEPROP 1 LAST TOLERANCE 1%
J 0
(13670 3950);
DISPLAY 0.638298 (13670 3950);
PAINT SKYBLUE (13670 3950);
FORCEPROP 1 LAST MATERIAL CHIP
J 0
(13665 3850);
DISPLAY 0.617021 (13665 3850);
PAINT SKYBLUE (13665 3850);
FORCEPROP 1 LAST PACK_TYPE 0402
J 0
(13665 3750);
DISPLAY 0.638298 (13665 3750);
PAINT SKYBLUE (13665 3750);
FORCEPROP 1 LASTPIN (13600 3825) $PN 2
J 0
(13605 3835);
DISPLAY 0.617021 (13605 3835);
PAINT GREEN (13605 3835);
FORCEPROP 1 LAST PART_NUMBER G21796-047
J 0
(13665 3800);
DISPLAY 0.617021 (13665 3800);
PAINT BLUE (13665 3800);
FORCEPROP 2 LAST SEC_TYPE 0402
J 0
(13650 4150);
DISPLAY 1.021277 (13650 4150);
PAINT ORANGE (13650 4150);
DISPLAY INVISIBLE (13650 4150);
FORCEPROP 2 LAST BOM_COST PROC_SOCKET
J 0
(13650 4150);
PAINT MONO (13650 4150);
DISPLAY INVISIBLE (13650 4150);
FORCEPROP 2 LAST SEC 1
J 0
(13650 4150);
DISPLAY 0.680851 (13650 4150);
PAINT MONO (13650 4150);
DISPLAY INVISIBLE (13650 4150);
FORCEPROP 1 LAST PATH I4
J 0
(13650 4100);
DISPLAY 0.978723 (13650 4100);
PAINT WHITE (13650 4100);
DISPLAY INVISIBLE (13650 4100);
FORCEPROP 2 LAST ROOM CPU1
J 0
(13650 4100);
PAINT MONO (13650 4100);
DISPLAY INVISIBLE (13650 4100);
FORCEPROP 2 LAST CDS_LIB mstr_discrete
J 0
(13600 3925);
PAINT ORANGE (13600 3925);
DISPLAY INVISIBLE (13600 3925);
FORCEPROP 2 LAST CDS_LOCATION R9N1
J 0
(13645 4050);
DISPLAY 0.617021 (13645 4050);
PAINT AQUA (13645 4050);
DISPLAY INVISIBLE (13645 4050);
FORCEADD OFFPAGE..4
(12225 2650);
FORCEPROP 2 LAST $XR0 90 
J 0
(12411 2650);
DISPLAY 0.638298 (12411 2650);
PAINT MONO (12411 2650);
FORCEPROP 2 LAST PATH I40
J 0
(12400 2725);
DISPLAY 1.021277 (12400 2725);
PAINT ORANGE (12400 2725);
DISPLAY INVISIBLE (12400 2725);
FORCEPROP 1 LAST OFFPAGE TRUE
J 0
(12550 2525);
DISPLAY 1.170213 (12550 2525);
PAINT GREEN (12550 2525);
DISPLAY INVISIBLE (12550 2525);
FORCEPROP 2 LAST CDS_LIB mstr_standard
J 0
(12225 2650);
PAINT MONO (12225 2650);
DISPLAY INVISIBLE (12225 2650);
FORCEPROP 1 LAST COMMENT_BODY TRUE
J 0
(12200 2550);
DISPLAY 1.170213 (12200 2550);
PAINT GREEN (12200 2550);
DISPLAY INVISIBLE (12200 2550);
FORCEADD OFFPAGE..4
(12225 2500);
FORCEPROP 2 LAST $XR0 90 
J 0
(12411 2500);
DISPLAY 0.638298 (12411 2500);
PAINT MONO (12411 2500);
FORCEPROP 2 LAST PATH I41
J 0
(12400 2575);
DISPLAY 1.021277 (12400 2575);
PAINT ORANGE (12400 2575);
DISPLAY INVISIBLE (12400 2575);
FORCEPROP 1 LAST OFFPAGE TRUE
J 0
(12550 2375);
DISPLAY 1.170213 (12550 2375);
PAINT GREEN (12550 2375);
DISPLAY INVISIBLE (12550 2375);
FORCEPROP 2 LAST CDS_LIB mstr_standard
J 0
(12225 2500);
PAINT MONO (12225 2500);
DISPLAY INVISIBLE (12225 2500);
FORCEPROP 1 LAST COMMENT_BODY TRUE
J 0
(12200 2400);
DISPLAY 1.170213 (12200 2400);
PAINT GREEN (12200 2400);
DISPLAY INVISIBLE (12200 2400);
FORCEADD OFFPAGE..4
(12225 2550);
FORCEPROP 2 LAST $XR0 90 
J 0
(12411 2550);
DISPLAY 0.638298 (12411 2550);
PAINT MONO (12411 2550);
FORCEPROP 2 LAST PATH I42
J 0
(12400 2625);
DISPLAY 1.021277 (12400 2625);
PAINT ORANGE (12400 2625);
DISPLAY INVISIBLE (12400 2625);
FORCEPROP 1 LAST OFFPAGE TRUE
J 0
(12550 2425);
DISPLAY 1.170213 (12550 2425);
PAINT GREEN (12550 2425);
DISPLAY INVISIBLE (12550 2425);
FORCEPROP 2 LAST CDS_LIB mstr_standard
J 0
(12225 2550);
PAINT MONO (12225 2550);
DISPLAY INVISIBLE (12225 2550);
FORCEPROP 1 LAST COMMENT_BODY TRUE
J 0
(12200 2450);
DISPLAY 1.170213 (12200 2450);
PAINT GREEN (12200 2450);
DISPLAY INVISIBLE (12200 2450);
FORCEADD OFFPAGE..3
(12200 2400);
FORCEPROP 2 LAST $XR0 97 
J 0
(12414 2400);
DISPLAY 0.638298 (12414 2400);
PAINT MONO (12414 2400);
FORCEPROP 2 LAST PATH I43
J 0
(12400 2475);
DISPLAY 1.021277 (12400 2475);
PAINT ORANGE (12400 2475);
DISPLAY INVISIBLE (12400 2475);
FORCEPROP 1 LAST OFFPAGE TRUE
J 0
(12525 2275);
DISPLAY 1.170213 (12525 2275);
PAINT GREEN (12525 2275);
DISPLAY INVISIBLE (12525 2275);
FORCEPROP 2 LAST CDS_LIB mstr_standard
J 0
(12200 2400);
PAINT MONO (12200 2400);
DISPLAY INVISIBLE (12200 2400);
FORCEPROP 1 LAST COMMENT_BODY TRUE
J 0
(12150 2300);
DISPLAY 1.170213 (12150 2300);
PAINT GREEN (12150 2300);
DISPLAY INVISIBLE (12150 2300);
FORCEADD OFFPAGE..4
(12225 2450);
FORCEPROP 2 LAST $XR0 90 
J 0
(12411 2450);
DISPLAY 0.638298 (12411 2450);
PAINT MONO (12411 2450);
FORCEPROP 2 LAST PATH I44
J 0
(12400 2525);
DISPLAY 1.021277 (12400 2525);
PAINT ORANGE (12400 2525);
DISPLAY INVISIBLE (12400 2525);
FORCEPROP 1 LAST OFFPAGE TRUE
J 0
(12550 2325);
DISPLAY 1.170213 (12550 2325);
PAINT GREEN (12550 2325);
DISPLAY INVISIBLE (12550 2325);
FORCEPROP 2 LAST CDS_LIB mstr_standard
J 0
(12225 2450);
PAINT MONO (12225 2450);
DISPLAY INVISIBLE (12225 2450);
FORCEPROP 1 LAST COMMENT_BODY TRUE
J 0
(12200 2350);
DISPLAY 1.170213 (12200 2350);
PAINT GREEN (12200 2350);
DISPLAY INVISIBLE (12200 2350);
FORCEADD OFFPAGE..2
(12575 800);
FORCEPROP 2 LAST $XR0 112 
J 0
(12764 800);
DISPLAY 0.638298 (12764 800);
PAINT MONO (12764 800);
FORCEPROP 2 LAST PATH I57
J 0
(12750 875);
DISPLAY 1.021277 (12750 875);
PAINT ORANGE (12750 875);
DISPLAY INVISIBLE (12750 875);
FORCEPROP 2 LAST CDS_LIB mstr_standard
J 0
(12575 800);
PAINT MONO (12575 800);
DISPLAY INVISIBLE (12575 800);
FORCEPROP 1 LAST COMMENT_BODY TRUE
J 0
(12530 705);
DISPLAY 1.170213 (12530 705);
PAINT GREEN (12530 705);
DISPLAY INVISIBLE (12530 705);
FORCEPROP 1 LAST OFFPAGE TRUE
J 0
(12900 675);
DISPLAY 1.170213 (12900 675);
PAINT GREEN (12900 675);
DISPLAY INVISIBLE (12900 675);
FORCEADD OFFPAGE..1
(7975 4150);
FORCEPROP 2 LAST $XR0 103 
J 0
(7723 4150);
DISPLAY 0.638298 (7723 4150);
PAINT MONO (7723 4150);
FORCEPROP 1 LAST OFFPAGE TRUE
J 0
(8300 4025);
DISPLAY 1.170213 (8300 4025);
PAINT GREEN (8300 4025);
DISPLAY INVISIBLE (8300 4025);
FORCEPROP 2 LAST CDS_LIB mstr_standard
J 0
(7975 4150);
PAINT MONO (7975 4150);
DISPLAY INVISIBLE (7975 4150);
FORCEPROP 2 LAST PATH I58
J 0
(7725 4200);
DISPLAY 1.021277 (7725 4200);
PAINT ORANGE (7725 4200);
DISPLAY INVISIBLE (7725 4200);
FORCEPROP 1 LAST COMMENT_BODY TRUE
J 0
(8100 4050);
DISPLAY 1.170213 (8100 4050);
PAINT GREEN (8100 4050);
DISPLAY INVISIBLE (8100 4050);
FORCEADD OFFPAGE..1
(7975 4100);
FORCEPROP 2 LAST $XR0 103 
J 0
(7723 4100);
DISPLAY 0.638298 (7723 4100);
PAINT MONO (7723 4100);
FORCEPROP 1 LAST OFFPAGE TRUE
J 0
(8300 3975);
DISPLAY 1.170213 (8300 3975);
PAINT GREEN (8300 3975);
DISPLAY INVISIBLE (8300 3975);
FORCEPROP 2 LAST CDS_LIB mstr_standard
J 0
(7975 4100);
PAINT MONO (7975 4100);
DISPLAY INVISIBLE (7975 4100);
FORCEPROP 2 LAST PATH I59
J 0
(7725 4150);
DISPLAY 1.021277 (7725 4150);
PAINT ORANGE (7725 4150);
DISPLAY INVISIBLE (7725 4150);
FORCEPROP 1 LAST COMMENT_BODY TRUE
J 0
(8100 4000);
DISPLAY 1.170213 (8100 4000);
PAINT GREEN (8100 4000);
DISPLAY INVISIBLE (8100 4000);
FORCEADD PVCCIO_CPU1..1
(13325 4275);
FORCEPROP 3 LASTPIN (13325 4225) SIG_NAME PVCCIO_CPU1\g
J 0
(13335 4235);
DISPLAY 0.659574 (13335 4235);
PAINT MONO (13335 4235);
DISPLAY INVISIBLE (13335 4235);
FORCEPROP 1 LAST HDL_POWER PVCCIO_CPU1
J 1
(13325 4325);
DISPLAY 0.872340 (13325 4325);
PAINT GREEN (13325 4325);
DISPLAY INVISIBLE (13325 4325);
FORCEPROP 1 LAST PATH I6
J 0
(13375 4300);
DISPLAY 0.872340 (13375 4300);
PAINT AQUA (13375 4300);
DISPLAY INVISIBLE (13375 4300);
FORCEPROP 2 LAST CDS_LIB mstr_symbols
J 0
(13325 4275);
PAINT ORANGE (13325 4275);
DISPLAY INVISIBLE (13325 4275);
FORCEPROP 1 LAST VOLTAGE 1.1V
J 0
(13280 4232);
DISPLAY 0.340426 (13280 4232);
PAINT SKYBLUE (13280 4232);
DISPLAY INVISIBLE (13280 4232);
FORCEPROP 1 LAST BODY_TYPE PLUMBING
J 0
(13280 4232);
DISPLAY 0.340426 (13280 4232);
PAINT GREEN (13280 4232);
DISPLAY INVISIBLE (13280 4232);
FORCEADD OFFPAGE..1
(7975 3950);
FORCEPROP 2 LAST $XR0 103 
J 0
(7723 3950);
DISPLAY 0.638298 (7723 3950);
PAINT MONO (7723 3950);
FORCEPROP 1 LAST OFFPAGE TRUE
J 0
(8300 3825);
DISPLAY 1.170213 (8300 3825);
PAINT GREEN (8300 3825);
DISPLAY INVISIBLE (8300 3825);
FORCEPROP 1 LAST COMMENT_BODY TRUE
J 0
(8100 3850);
DISPLAY 1.170213 (8100 3850);
PAINT GREEN (8100 3850);
DISPLAY INVISIBLE (8100 3850);
FORCEPROP 2 LAST CDS_LIB mstr_standard
J 0
(7975 3950);
PAINT MONO (7975 3950);
DISPLAY INVISIBLE (7975 3950);
FORCEPROP 2 LAST PATH I60
J 0
(7725 4000);
DISPLAY 1.021277 (7725 4000);
PAINT ORANGE (7725 4000);
DISPLAY INVISIBLE (7725 4000);
FORCEADD OFFPAGE..1
(7975 4000);
FORCEPROP 2 LAST $XR0 103 
J 0
(7723 4000);
DISPLAY 0.638298 (7723 4000);
PAINT MONO (7723 4000);
FORCEPROP 1 LAST OFFPAGE TRUE
J 0
(8300 3875);
DISPLAY 1.170213 (8300 3875);
PAINT GREEN (8300 3875);
DISPLAY INVISIBLE (8300 3875);
FORCEPROP 1 LAST COMMENT_BODY TRUE
J 0
(8100 3900);
DISPLAY 1.170213 (8100 3900);
PAINT GREEN (8100 3900);
DISPLAY INVISIBLE (8100 3900);
FORCEPROP 2 LAST CDS_LIB mstr_standard
J 0
(7975 4000);
PAINT MONO (7975 4000);
DISPLAY INVISIBLE (7975 4000);
FORCEPROP 2 LAST PATH I61
J 0
(7725 4050);
DISPLAY 1.021277 (7725 4050);
PAINT ORANGE (7725 4050);
DISPLAY INVISIBLE (7725 4050);
FORCEADD OFFPAGE..1
(7975 3700);
FORCEPROP 2 LAST $XR0 96 
J 0
(7754 3700);
DISPLAY 0.638298 (7754 3700);
PAINT MONO (7754 3700);
FORCEPROP 1 LAST OFFPAGE TRUE
J 0
(8300 3575);
DISPLAY 1.170213 (8300 3575);
PAINT GREEN (8300 3575);
DISPLAY INVISIBLE (8300 3575);
FORCEPROP 1 LAST COMMENT_BODY TRUE
J 0
(8100 3600);
DISPLAY 1.170213 (8100 3600);
PAINT GREEN (8100 3600);
DISPLAY INVISIBLE (8100 3600);
FORCEPROP 2 LAST PATH I62
J 0
(8025 3775);
DISPLAY 1.021277 (8025 3775);
PAINT ORANGE (8025 3775);
DISPLAY INVISIBLE (8025 3775);
FORCEPROP 2 LAST CDS_LIB mstr_standard
J 0
(7975 3700);
PAINT MONO (7975 3700);
DISPLAY INVISIBLE (7975 3700);
FORCEADD OFFPAGE..1
(7975 3650);
FORCEPROP 2 LAST $XR0 96 
J 0
(7754 3650);
DISPLAY 0.638298 (7754 3650);
PAINT MONO (7754 3650);
FORCEPROP 1 LAST OFFPAGE TRUE
J 0
(8300 3525);
DISPLAY 1.170213 (8300 3525);
PAINT GREEN (8300 3525);
DISPLAY INVISIBLE (8300 3525);
FORCEPROP 2 LAST PATH I63
J 0
(8025 3725);
DISPLAY 1.021277 (8025 3725);
PAINT ORANGE (8025 3725);
DISPLAY INVISIBLE (8025 3725);
FORCEPROP 2 LAST CDS_LIB mstr_standard
J 0
(7975 3650);
PAINT MONO (7975 3650);
DISPLAY INVISIBLE (7975 3650);
FORCEPROP 1 LAST COMMENT_BODY TRUE
J 0
(8100 3550);
DISPLAY 1.170213 (8100 3550);
PAINT GREEN (8100 3550);
DISPLAY INVISIBLE (8100 3550);
FORCEADD OFFPAGE..5
(7950 3500);
FORCEPROP 2 LAST $XR5 88 
J 0
(7276 3500);
DISPLAY 0.638298 (7276 3500);
PAINT MONO (7276 3500);
FORCEPROP 2 LAST $XR4 87 
J 0
(7366 3500);
DISPLAY 0.638298 (7366 3500);
PAINT MONO (7366 3500);
FORCEPROP 2 LAST $XR3 86 
J 0
(7456 3500);
DISPLAY 0.638298 (7456 3500);
PAINT MONO (7456 3500);
FORCEPROP 2 LAST $XR2 85 
J 0
(7546 3500);
DISPLAY 0.638298 (7546 3500);
PAINT MONO (7546 3500);
FORCEPROP 2 LAST $XR1 84 
J 0
(7636 3500);
DISPLAY 0.638298 (7636 3500);
PAINT MONO (7636 3500);
FORCEPROP 2 LAST $XR0 83 
J 0
(7726 3500);
DISPLAY 0.638298 (7726 3500);
PAINT MONO (7726 3500);
FORCEPROP 1 LAST OFFPAGE TRUE
J 0
(8275 3375);
DISPLAY 1.170213 (8275 3375);
PAINT GREEN (8275 3375);
DISPLAY INVISIBLE (8275 3375);
FORCEPROP 2 LAST PATH I64
J 0
(8000 3575);
DISPLAY 1.021277 (8000 3575);
PAINT ORANGE (8000 3575);
DISPLAY INVISIBLE (8000 3575);
FORCEPROP 2 LAST CDS_LIB mstr_standard
J 0
(7950 3500);
PAINT MONO (7950 3500);
DISPLAY INVISIBLE (7950 3500);
FORCEPROP 1 LAST COMMENT_BODY TRUE
J 0
(8050 3425);
DISPLAY 1.170213 (8050 3425);
PAINT GREEN (8050 3425);
DISPLAY INVISIBLE (8050 3425);
FORCEADD OFFPAGE..5
(7950 3550);
FORCEPROP 2 LAST $XR5 82 
J 0
(7276 3550);
DISPLAY 0.638298 (7276 3550);
PAINT MONO (7276 3550);
FORCEPROP 2 LAST $XR4 81 
J 0
(7366 3550);
DISPLAY 0.638298 (7366 3550);
PAINT MONO (7366 3550);
FORCEPROP 2 LAST $XR3 80 
J 0
(7456 3550);
DISPLAY 0.638298 (7456 3550);
PAINT MONO (7456 3550);
FORCEPROP 2 LAST $XR2 79 
J 0
(7546 3550);
DISPLAY 0.638298 (7546 3550);
PAINT MONO (7546 3550);
FORCEPROP 2 LAST $XR1 78 
J 0
(7636 3550);
DISPLAY 0.638298 (7636 3550);
PAINT MONO (7636 3550);
FORCEPROP 2 LAST $XR0 77 
J 0
(7726 3550);
DISPLAY 0.638298 (7726 3550);
PAINT MONO (7726 3550);
FORCEPROP 1 LAST OFFPAGE TRUE
J 0
(8275 3425);
DISPLAY 1.170213 (8275 3425);
PAINT GREEN (8275 3425);
DISPLAY INVISIBLE (8275 3425);
FORCEPROP 2 LAST PATH I65
J 0
(8000 3625);
DISPLAY 1.021277 (8000 3625);
PAINT ORANGE (8000 3625);
DISPLAY INVISIBLE (8000 3625);
FORCEPROP 2 LAST CDS_LIB mstr_standard
J 0
(7950 3550);
PAINT MONO (7950 3550);
DISPLAY INVISIBLE (7950 3550);
FORCEPROP 1 LAST COMMENT_BODY TRUE
J 0
(8050 3475);
DISPLAY 1.170213 (8050 3475);
PAINT GREEN (8050 3475);
DISPLAY INVISIBLE (8050 3475);
FORCEADD OFFPAGE..6
(7975 3400);
FORCEPROP 2 LAST $XR2 152 
J 0
(7516 3400);
DISPLAY 0.638298 (7516 3400);
PAINT MONO (7516 3400);
FORCEPROP 2 LAST $XR1 95 
J 0
(7636 3400);
DISPLAY 0.638298 (7636 3400);
PAINT MONO (7636 3400);
FORCEPROP 2 LAST $XR0 94 
J 0
(7726 3400);
DISPLAY 0.638298 (7726 3400);
PAINT MONO (7726 3400);
FORCEPROP 1 LAST OFFPAGE TRUE
J 0
(8300 3275);
DISPLAY 1.170213 (8300 3275);
PAINT GREEN (8300 3275);
DISPLAY INVISIBLE (8300 3275);
FORCEPROP 2 LAST PATH I67
J 0
(8025 3475);
DISPLAY 1.021277 (8025 3475);
PAINT ORANGE (8025 3475);
DISPLAY INVISIBLE (8025 3475);
FORCEPROP 2 LAST CDS_LIB mstr_standard
J 0
(7975 3400);
PAINT MONO (7975 3400);
DISPLAY INVISIBLE (7975 3400);
FORCEPROP 1 LAST COMMENT_BODY TRUE
J 0
(8075 3325);
DISPLAY 1.170213 (8075 3325);
PAINT GREEN (8075 3325);
DISPLAY INVISIBLE (8075 3325);
FORCEADD OFFPAGE..6
(7975 3350);
FORCEPROP 2 LAST $XR2 152 
J 0
(7516 3350);
DISPLAY 0.638298 (7516 3350);
PAINT MONO (7516 3350);
FORCEPROP 2 LAST $XR1 95 
J 0
(7636 3350);
DISPLAY 0.638298 (7636 3350);
PAINT MONO (7636 3350);
FORCEPROP 2 LAST $XR0 94 
J 0
(7726 3350);
DISPLAY 0.638298 (7726 3350);
PAINT MONO (7726 3350);
FORCEPROP 1 LAST OFFPAGE TRUE
J 0
(8300 3225);
DISPLAY 1.170213 (8300 3225);
PAINT GREEN (8300 3225);
DISPLAY INVISIBLE (8300 3225);
FORCEPROP 2 LAST PATH I68
J 0
(8025 3425);
DISPLAY 1.021277 (8025 3425);
PAINT ORANGE (8025 3425);
DISPLAY INVISIBLE (8025 3425);
FORCEPROP 2 LAST CDS_LIB mstr_standard
J 0
(7975 3350);
PAINT MONO (7975 3350);
DISPLAY INVISIBLE (7975 3350);
FORCEPROP 1 LAST COMMENT_BODY TRUE
J 0
(8075 3275);
DISPLAY 1.170213 (8075 3275);
PAINT GREEN (8075 3275);
DISPLAY INVISIBLE (8075 3275);
FORCEADD RES..2
(13325 3925);
FORCEPROP 1 LAST VALUE 100.0
J 0
(13370 4000);
DISPLAY 0.617021 (13370 4000);
PAINT SKYBLUE (13370 4000);
FORCEPROP 1 LAST LOCATION R9N2
J 0
(13370 4050);
DISPLAY 0.617021 (13370 4050);
PAINT AQUA (13370 4050);
FORCEPROP 1 LAST WATTAGE 1/16W
J 0
(13365 3900);
DISPLAY 0.638298 (13365 3900);
PAINT SKYBLUE (13365 3900);
FORCEPROP 1 LAST MATERIAL CHIP
J 0
(13365 3850);
DISPLAY 0.617021 (13365 3850);
PAINT SKYBLUE (13365 3850);
FORCEPROP 1 LAST PART_NUMBER G21796-017
J 0
(13365 3800);
DISPLAY 0.617021 (13365 3800);
PAINT BLUE (13365 3800);
FORCEPROP 1 LAST PACK_TYPE 0402
J 0
(13365 3750);
DISPLAY 0.638298 (13365 3750);
PAINT SKYBLUE (13365 3750);
FORCEPROP 1 LAST TOLERANCE 1%
J 0
(13370 3950);
DISPLAY 0.638298 (13370 3950);
PAINT SKYBLUE (13370 3950);
FORCEPROP 1 LASTPIN (13325 3825) $PN 2
J 0
(13330 3835);
DISPLAY 0.617021 (13330 3835);
PAINT GREEN (13330 3835);
FORCEPROP 1 LASTPIN (13325 4025) $PN 1
J 0
(13330 3987);
DISPLAY 0.617021 (13330 3987);
PAINT GREEN (13330 3987);
FORCEPROP 2 LAST ROOM CPU1
J 0
(13375 4100);
PAINT MONO (13375 4100);
DISPLAY INVISIBLE (13375 4100);
FORCEPROP 1 LAST PATH I7
J 0
(13375 4100);
DISPLAY 0.978723 (13375 4100);
PAINT WHITE (13375 4100);
DISPLAY INVISIBLE (13375 4100);
FORCEPROP 2 LAST SEC 1
J 0
(13375 4150);
DISPLAY 0.680851 (13375 4150);
PAINT MONO (13375 4150);
DISPLAY INVISIBLE (13375 4150);
FORCEPROP 2 LAST BOM_COST PROC_SOCKET
J 0
(13375 4150);
PAINT MONO (13375 4150);
DISPLAY INVISIBLE (13375 4150);
FORCEPROP 2 LAST SEC_TYPE 0402
J 0
(13375 4150);
DISPLAY 1.021277 (13375 4150);
PAINT ORANGE (13375 4150);
DISPLAY INVISIBLE (13375 4150);
FORCEPROP 2 LAST CDS_LOCATION R9N2
J 0
(13370 4050);
DISPLAY 0.617021 (13370 4050);
PAINT AQUA (13370 4050);
DISPLAY INVISIBLE (13370 4050);
FORCEPROP 2 LAST CDS_LIB mstr_discrete
J 0
(13325 3925);
PAINT ORANGE (13325 3925);
DISPLAY INVISIBLE (13325 3925);
FORCEADD OFFPAGE..5
(7950 3150);
FORCEPROP 2 LAST $XR0 100 
J 0
(7695 3150);
DISPLAY 0.638298 (7695 3150);
PAINT MONO (7695 3150);
FORCEPROP 1 LAST OFFPAGE TRUE
J 0
(8275 3025);
DISPLAY 1.170213 (8275 3025);
PAINT GREEN (8275 3025);
DISPLAY INVISIBLE (8275 3025);
FORCEPROP 2 LAST PATH I70
J 0
(8000 3225);
DISPLAY 1.021277 (8000 3225);
PAINT ORANGE (8000 3225);
DISPLAY INVISIBLE (8000 3225);
FORCEPROP 1 LAST COMMENT_BODY TRUE
J 0
(8050 3075);
DISPLAY 1.170213 (8050 3075);
PAINT GREEN (8050 3075);
DISPLAY INVISIBLE (8050 3075);
FORCEPROP 2 LAST CDS_LIB mstr_standard
J 0
(7950 3150);
PAINT MONO (7950 3150);
DISPLAY INVISIBLE (7950 3150);
FORCEADD OFFPAGE..5
(7950 3000);
FORCEPROP 2 LAST $XR0 100 
J 0
(7695 3000);
DISPLAY 0.638298 (7695 3000);
PAINT MONO (7695 3000);
FORCEPROP 1 LAST OFFPAGE TRUE
J 0
(8275 2875);
DISPLAY 1.170213 (8275 2875);
PAINT GREEN (8275 2875);
DISPLAY INVISIBLE (8275 2875);
FORCEPROP 2 LAST PATH I73
J 0
(8000 3075);
DISPLAY 1.021277 (8000 3075);
PAINT ORANGE (8000 3075);
DISPLAY INVISIBLE (8000 3075);
FORCEPROP 2 LAST CDS_LIB mstr_standard
J 0
(7950 3000);
PAINT MONO (7950 3000);
DISPLAY INVISIBLE (7950 3000);
FORCEPROP 1 LAST COMMENT_BODY TRUE
J 0
(8050 2925);
DISPLAY 1.170213 (8050 2925);
PAINT GREEN (8050 2925);
DISPLAY INVISIBLE (8050 2925);
FORCEADD OFFPAGE..4
(12800 4150);
FORCEPROP 2 LAST $XR0 96 
J 0
(12986 4150);
DISPLAY 0.638298 (12986 4150);
PAINT MONO (12986 4150);
FORCEPROP 2 LAST PATH I8
J 0
(13100 4200);
DISPLAY 1.021277 (13100 4200);
PAINT ORANGE (13100 4200);
DISPLAY INVISIBLE (13100 4200);
FORCEPROP 2 LAST CDS_LIB mstr_standard
J 0
(12800 4150);
PAINT MONO (12800 4150);
DISPLAY INVISIBLE (12800 4150);
FORCEPROP 1 LAST COMMENT_BODY TRUE
J 0
(12775 4050);
DISPLAY 1.170213 (12775 4050);
PAINT GREEN (12775 4050);
DISPLAY INVISIBLE (12775 4050);
FORCEPROP 1 LAST OFFPAGE TRUE
J 0
(13125 4025);
DISPLAY 1.170213 (13125 4025);
PAINT GREEN (13125 4025);
DISPLAY INVISIBLE (13125 4025);
FORCEADD OFFPAGE..5
(8225 2550);
FORCEPROP 2 LAST $XR0 99 
J 0
(8001 2550);
DISPLAY 0.638298 (8001 2550);
PAINT MONO (8001 2550);
FORCEPROP 2 LAST PATH I80
J 0
(8275 2625);
DISPLAY 1.021277 (8275 2625);
PAINT ORANGE (8275 2625);
DISPLAY INVISIBLE (8275 2625);
FORCEPROP 2 LAST CDS_LIB mstr_standard
J 0
(8225 2550);
PAINT MONO (8225 2550);
DISPLAY INVISIBLE (8225 2550);
FORCEPROP 1 LAST OFFPAGE TRUE
J 0
(8550 2425);
DISPLAY 1.170213 (8550 2425);
PAINT GREEN (8550 2425);
DISPLAY INVISIBLE (8550 2425);
FORCEPROP 1 LAST COMMENT_BODY TRUE
J 0
(8325 2475);
DISPLAY 1.170213 (8325 2475);
PAINT GREEN (8325 2475);
DISPLAY INVISIBLE (8325 2475);
FORCEADD OFFPAGE..5
(8225 2500);
FORCEPROP 2 LAST $XR0 99 
J 0
(8001 2500);
DISPLAY 0.638298 (8001 2500);
PAINT MONO (8001 2500);
FORCEPROP 2 LAST PATH I81
J 0
(8275 2575);
DISPLAY 1.021277 (8275 2575);
PAINT ORANGE (8275 2575);
DISPLAY INVISIBLE (8275 2575);
FORCEPROP 1 LAST OFFPAGE TRUE
J 0
(8550 2375);
DISPLAY 1.170213 (8550 2375);
PAINT GREEN (8550 2375);
DISPLAY INVISIBLE (8550 2375);
FORCEPROP 1 LAST COMMENT_BODY TRUE
J 0
(8325 2425);
DISPLAY 1.170213 (8325 2425);
PAINT GREEN (8325 2425);
DISPLAY INVISIBLE (8325 2425);
FORCEPROP 2 LAST CDS_LIB mstr_standard
J 0
(8225 2500);
PAINT MONO (8225 2500);
DISPLAY INVISIBLE (8225 2500);
FORCEADD OFFPAGE..5
(8225 2450);
FORCEPROP 2 LAST $XR0 99 
J 0
(8001 2450);
DISPLAY 0.638298 (8001 2450);
PAINT MONO (8001 2450);
FORCEPROP 2 LAST PATH I82
J 0
(8275 2525);
DISPLAY 1.021277 (8275 2525);
PAINT ORANGE (8275 2525);
DISPLAY INVISIBLE (8275 2525);
FORCEPROP 1 LAST OFFPAGE TRUE
J 0
(8550 2325);
DISPLAY 1.170213 (8550 2325);
PAINT GREEN (8550 2325);
DISPLAY INVISIBLE (8550 2325);
FORCEPROP 1 LAST COMMENT_BODY TRUE
J 0
(8325 2375);
DISPLAY 1.170213 (8325 2375);
PAINT GREEN (8325 2375);
DISPLAY INVISIBLE (8325 2375);
FORCEPROP 2 LAST CDS_LIB mstr_standard
J 0
(8225 2450);
PAINT MONO (8225 2450);
DISPLAY INVISIBLE (8225 2450);
FORCEADD OFFPAGE..5
(8225 2400);
FORCEPROP 2 LAST $XR0 99 
J 0
(8001 2400);
DISPLAY 0.638298 (8001 2400);
PAINT MONO (8001 2400);
FORCEPROP 1 LAST OFFPAGE TRUE
J 0
(8550 2275);
DISPLAY 1.170213 (8550 2275);
PAINT GREEN (8550 2275);
DISPLAY INVISIBLE (8550 2275);
FORCEPROP 1 LAST COMMENT_BODY TRUE
J 0
(8325 2325);
DISPLAY 1.170213 (8325 2325);
PAINT GREEN (8325 2325);
DISPLAY INVISIBLE (8325 2325);
FORCEPROP 2 LAST PATH I83
J 0
(8275 2475);
DISPLAY 1.021277 (8275 2475);
PAINT ORANGE (8275 2475);
DISPLAY INVISIBLE (8275 2475);
FORCEPROP 2 LAST CDS_LIB mstr_standard
J 0
(8225 2400);
PAINT MONO (8225 2400);
DISPLAY INVISIBLE (8225 2400);
FORCEADD BOM_NOTE..1
(6675 4450);
FORCEPROP 0 LAST L1 ASSEMBLY IPN PRIMARY :H63715-002,
J 0
(6525 4325);
DISPLAY 0.851064 (6525 4325);
PAINT WHITE (6525 4325);
FORCEPROP 2 LAST CDS_LIB mstr_symbols
J 0
(6675 4450);
PAINT ORANGE (6675 4450);
DISPLAY INVISIBLE (6675 4450);
FORCEPROP 2 LAST BOM_COST SB
J 0
(6525 4425);
DISPLAY 1.361702 (6525 4425);
PAINT ORANGE (6525 4425);
DISPLAY INVISIBLE (6525 4425);
FORCEPROP 2 LAST ROOM SB_HEADERS
J 0
(6525 4425);
DISPLAY 1.361702 (6525 4425);
PAINT ORANGE (6525 4425);
DISPLAY INVISIBLE (6525 4425);
FORCEPROP 1 LAST COMMENT_BODY TRUE
J 0
(6700 4550);
DISPLAY 1.319149 (6700 4550);
PAINT ORANGE (6700 4550);
DISPLAY INVISIBLE (6700 4550);
FORCEADD CAD_NOTE..1
(6575 850);
FORCEPROP 0 LAST LINE PLACE RBIAS RESISTORS
J 0
(6425 725);
PAINT WHITE (6425 725);
FORCEPROP 0 LAST LINE2 WITHIN 1.1 OF CPU PINS
J 0
(6425 650);
PAINT WHITE (6425 650);
FORCEPROP 2 LAST CDS_LIB mstr_symbols
J 0
(6575 850);
PAINT ORANGE (6575 850);
DISPLAY INVISIBLE (6575 850);
FORCEPROP 1 LAST COMMENT_BODY TRUE
J 0
(6600 950);
DISPLAY 1.340426 (6600 950);
PAINT GREEN (6600 950);
DISPLAY INVISIBLE (6600 950);
FORCEADD DESIGN_NOTE..1
(13300 1675);
FORCEPROP 0 LAST L1 CPU1 PIROM ADDRESS: 0XA2
J 0
(13100 1550);
DISPLAY 1.021277 (13100 1550);
PAINT ORANGE (13100 1550);
FORCEPROP 1 LAST COMMENT_BODY TRUE
J 0
(13325 1775);
DISPLAY 0.978723 (13325 1775);
PAINT ORANGE (13325 1775);
DISPLAY INVISIBLE (13325 1775);
FORCEPROP 2 LAST CDS_LIB mstr_symbols
J 0
(13300 1675);
PAINT ORANGE (13300 1675);
DISPLAY INVISIBLE (13300 1675);
FORCEADD PRELIM..10
(10260 2490);
PAINT GRAY (10260 2490);
FORCEPROP 2 LAST CDS_LIB mstr_misc
J 0
(10260 2490);
PAINT ORANGE (10260 2490);
DISPLAY INVISIBLE (10260 2490);
FORCEPROP 1 LAST COMMENT_BODY TRUE
J 0
(10260 2490);
PAINT ORANGE (10260 2490);
DISPLAY INVISIBLE (10260 2490);
FORCEADD DESIGN_NOTE..1
(9650 525);
FORCEPROP 0 LAST L1 CPU SYMBOLS 1-30 ARE PRELIMINARY AND SUBJECT TO CHANGE
J 0
(9450 400);
DISPLAY 1.021277 (9450 400);
PAINT ORANGE (9450 400);
FORCEPROP 1 LAST COMMENT_BODY TRUE
J 0
(9675 625);
DISPLAY 0.978723 (9675 625);
PAINT ORANGE (9675 625);
DISPLAY INVISIBLE (9675 625);
FORCEPROP 2 LAST CDS_LIB mstr_symbols
J 0
(9650 525);
PAINT ORANGE (9650 525);
DISPLAY INVISIBLE (9650 525);
FORCEADD CAD_NOTE..1
(6900 2250);
FORCEPROP 0 LAST LINE2 WITHIN 1 OF CPU PINS
J 0
(6750 2050);
PAINT WHITE (6750 2050);
FORCEPROP 0 LAST LINE PLACE RCOMP RESISTORS
J 0
(6750 2125);
PAINT WHITE (6750 2125);
FORCEPROP 1 LAST COMMENT_BODY TRUE
J 0
(6925 2350);
DISPLAY 1.340426 (6925 2350);
PAINT GREEN (6925 2350);
DISPLAY INVISIBLE (6925 2350);
FORCEPROP 2 LAST CDS_LIB mstr_symbols
J 0
(6900 2250);
PAINT ORANGE (6900 2250);
DISPLAY INVISIBLE (6900 2250);
FORCEADD INTEL_CORP_BPAGE..1
(14300 -325);
FORCEPROP 1 LAST CDS_CON_LAST_MODIFIED Fri Jun 16 17:48:22 2017
J 0
(12875 0);
PAINT ORANGE (12875 0);
DISPLAY INVISIBLE (12875 0);
FORCEPROP 1 LAST CUSTOM_TXT_CDS <CURRENT_DESIGN_SHEET> OF <TOTAL_DESIGN_SHEETS>
J 0
(13800 -300);
PAINT ORANGE (13800 -300);
FORCEPROP 1 LAST CUSTOM_TXT_CDS <CON_LAST_MODIFIED>
J 0
(10300 -225);
PAINT ORANGE (10300 -225);
FORCEPROP 2 LAST CUSTOM_TXT_CDS <XR_PAGE_TITLE>
J 0
(6410 4925);
DISPLAY 0.638298 (6410 4925);
PAINT PINK (6410 4925);
DISPLAY INVISIBLE (6410 4925);
FORCEPROP 1 LAST SCH_TITLE SKYLAKE - SKT1 - 1 OF 21
J 0
(6350 -275);
DISPLAY 1.212766 (6350 -275);
PAINT ORANGE (6350 -275);
FORCEPROP 1 LAST COMMENT_BODY TRUE
J 0
(14312 -313);
DISPLAY 0.468085 (14312 -313);
PAINT GREEN (14312 -313);
DISPLAY INVISIBLE (14312 -313);
FORCEPROP 2 LAST CDS_LIB mstr_symbols
J 0
(14300 -325);
PAINT MONO (14300 -325);
DISPLAY INVISIBLE (14300 -325);
FORCEPROP 2 LAST PAGE_BORDER TRUE
J 0
(6410 4925);
DISPLAY 0.638298 (6410 4925);
PAINT PINK (6410 4925);
DISPLAY INVISIBLE (6410 4925);
FORCEPROP 2 LAST CDS_XR_PAGE_TITLE CR-55 : @BASEBOARD_FAB2_LIB.BASEBOARD_FAB2(SCH_1):PAGE55
J 0
(6410 4925);
DISPLAY 0.638298 (6410 4925);
PAINT PINK (6410 4925);
DISPLAY INVISIBLE (6410 4925);
WIRE 16 -1 (6650 2350)(6650 2300);
WIRE 16 -1 (6650 2350)(6800 2350);
WIRE 16 -1 (6575 2350)(6650 2350);
WIRE 16 -1 (6575 2625)(6575 2350);
WIRE 16 -1 (6800 2350)(7025 2350);
WIRE 16 -1 (6800 2550)(6800 2350);
WIRE 16 -1 (7250 2350)(7025 2350);
WIRE 16 -1 (7025 2500)(7025 2350);
WIRE 16 -1 (7250 2350)(7475 2350);
WIRE 16 -1 (7250 2425)(7250 2350);
WIRE 16 -1 (7700 2350)(7475 2350);
WIRE 16 -1 (7475 2425)(7475 2350);
WIRE 16 -1 (7700 2350)(7700 2425);
WIRE 16 -1 (6600 1150)(6600 1200);
WIRE 16 -1 (6600 1200)(6825 1200);
WIRE 16 -1 (6600 1325)(6600 1200);
WIRE 16 -1 (6825 1200)(7050 1200);
WIRE 16 -1 (6825 1325)(6825 1200);
WIRE 16 -1 (7050 1200)(7275 1200);
WIRE 16 -1 (7050 1325)(7050 1200);
WIRE 16 -1 (7500 1200)(7275 1200);
WIRE 16 -1 (7275 1325)(7275 1200);
WIRE 16 -1 (7500 1325)(7500 1200);
WIRE 16 -1 (13600 2550)(13600 2500);
WIRE 16 -1 (13350 2500)(13600 2500);
WIRE 16 -1 (13600 2500)(13600 2400);
WIRE 16 -1 (13350 2500)(13100 2500);
WIRE 16 -1 (13350 2400)(13350 2500);
WIRE 16 -1 (13100 2500)(12850 2500);
WIRE 16 -1 (13100 2400)(13100 2500);
WIRE 16 -1 (12600 2500)(12850 2500);
WIRE 16 -1 (12850 2400)(12850 2500);
WIRE 16 -1 (12600 2400)(12600 2500);
WIRE 16 -1 (13275 1200)(13275 1275);
WIRE 16 -1 (13950 2875)(13950 2925);
WIRE 16 -1 (13600 2875)(13950 2875);
WIRE 16 -1 (13325 2875)(13600 2875);
WIRE 16 -1 (13600 3100)(13600 2875);
WIRE 16 -1 (13325 3100)(13325 2875);
WIRE 16 -1 (13325 4175)(13325 4225);
WIRE 16 -1 (13325 4175)(13600 4175);
WIRE 16 -1 (13325 4025)(13325 4175);
WIRE 16 -1 (13600 4025)(13600 4175);
WIRE 16 -1 (12175 2900)(11175 2900);
FORCEPROP 2 LAST SIG_NAME TP_CPU1_PROC_DIS_G_N
J 0
(11425 2910);
DISPLAY 0.617021 (11425 2910);
PAINT ORANGE (11425 2910);
FORCEPROP 2 LASTPROP $XRERR UNIQUE?
J 0
(12205 2900);
DISPLAY 0.638298 (12205 2900);
PAINT MONO (12205 2900);
DISPLAY INVISIBLE (12205 2900);
WIRE 16 -1 (9275 3200)(8000 3200);
FORCEPROP 2 LAST SIG_NAME M_L_CPU_VREF
J 0
(8025 3210);
DISPLAY 0.617021 (8025 3210);
PAINT ORANGE (8025 3210);
WIRE 16 -1 (9275 3400)(8025 3400);
FORCEPROP 2 LAST SIG_NAME H_CPU1_MEMGHJ_MEMHOT_G_N
J 0
(8050 3410);
DISPLAY 0.617021 (8050 3410);
PAINT ORANGE (8050 3410);
WIRE 16 -1 (9275 3950)(8025 3950);
FORCEPROP 2 LAST SIG_NAME CLK_100M_CPU1_BCLK1_DN
J 0
(8050 3960);
DISPLAY 0.617021 (8050 3960);
PAINT ORANGE (8050 3960);
WIRE 16 -1 (9275 3250)(8000 3250);
FORCEPROP 2 LAST SIG_NAME M_M_CPU_VREF
J 0
(8025 3260);
DISPLAY 0.617021 (8025 3260);
PAINT ORANGE (8025 3260);
WIRE 16 -1 (13700 1850)(13600 1850);
WIRE 16 -1 (13600 2200)(13600 1850);
WIRE 16 -1 (11175 1850)(13600 1850);
FORCEPROP 2 LAST SIG_NAME FM_CPU1_PKGID0
J 0
(11425 1860);
DISPLAY 0.617021 (11425 1860);
PAINT ORANGE (11425 1860);
WIRE 16 -1 (9275 3800)(8025 3800);
FORCEPROP 2 LAST SIG_NAME CLK_100M_CPU1_BCLK2_DN
J 0
(8050 3810);
DISPLAY 0.617021 (8050 3810);
PAINT ORANGE (8050 3810);
WIRE 16 -1 (13350 1900)(11175 1900);
FORCEPROP 2 LAST SIG_NAME FM_CPU1_PKGID1
J 0
(11425 1910);
DISPLAY 0.617021 (11425 1910);
PAINT ORANGE (11425 1910);
WIRE 16 -1 (13700 1900)(13350 1900);
WIRE 16 -1 (13350 2200)(13350 1900);
WIRE 16 -1 (6575 2825)(6575 2900);
WIRE 16 -1 (6575 2900)(9275 2900);
FORCEPROP 2 LAST SIG_NAME A_CPU1_GHJ_RCOMP2
J 0
(8050 2910);
DISPLAY 0.617021 (8050 2910);
PAINT ORANGE (8050 2910);
FORCEPROP 2 LASTPROP $XRERR UNIQUE?
J 0
(7810 2910);
DISPLAY 0.638298 (7810 2910);
PAINT MONO (7810 2910);
DISPLAY INVISIBLE (7810 2910);
WIRE 16 -1 (7025 2700)(7025 2800);
WIRE 16 -1 (9275 2800)(7025 2800);
FORCEPROP 2 LAST SIG_NAME A_CPU1_GHJ_RCOMP0
J 0
(8050 2810);
DISPLAY 0.617021 (8050 2810);
PAINT ORANGE (8050 2810);
FORCEPROP 2 LASTPROP $XRERR UNIQUE?
J 0
(7810 2810);
DISPLAY 0.638298 (7810 2810);
PAINT MONO (7810 2810);
DISPLAY INVISIBLE (7810 2810);
WIRE 16 -1 (9275 3050)(8000 3050);
FORCEPROP 2 LAST SIG_NAME M_H_CPU_VREF
J 0
(8025 3060);
DISPLAY 0.617021 (8025 3060);
PAINT ORANGE (8025 3060);
WIRE 16 -1 (12150 3300)(11175 3300);
FORCEPROP 2 LAST SIG_NAME H_CPU1_CATERR_G_N
J 0
(11425 3310);
DISPLAY 0.617021 (11425 3310);
PAINT ORANGE (11425 3310);
WIRE 16 -1 (13600 3300)(13600 3400);
WIRE 16 -1 (13700 3400)(13600 3400);
WIRE 16 -1 (12350 3400)(13600 3400);
FORCEPROP 2 LAST SIG_NAME SVID_ALERT0_CPU1_R_N
J 0
(12850 3410);
DISPLAY 0.617021 (12850 3410);
PAINT ORANGE (12850 3410);
WIRE 16 -1 (13325 3300)(13325 3500);
WIRE 16 -1 (13675 3500)(13325 3500);
WIRE 16 -1 (12350 3500)(13325 3500);
FORCEPROP 2 LAST SIG_NAME SVID_DIO0_CPU1_R
J 0
(12850 3510);
DISPLAY 0.617021 (12850 3510);
PAINT ORANGE (12850 3510);
WIRE 16 -1 (13700 3550)(13600 3550);
WIRE 16 -1 (13600 3825)(13600 3550);
WIRE 16 -1 (12350 3550)(13600 3550);
FORCEPROP 2 LAST SIG_NAME SVID_ALERT1_CPU1_R_N
J 0
(12850 3560);
DISPLAY 0.617021 (12850 3560);
PAINT ORANGE (12850 3560);
WIRE 16 -1 (13325 3650)(12350 3650);
FORCEPROP 2 LAST SIG_NAME SVID_DIO1_CPU1_R
J 0
(12850 3660);
DISPLAY 0.617021 (12850 3660);
PAINT ORANGE (12850 3660);
WIRE 16 -1 (13325 3825)(13325 3650);
WIRE 16 -1 (13675 3650)(13325 3650);
WIRE 16 -1 (12350 3600)(13700 3600);
FORCEPROP 2 LAST SIG_NAME SVID_CLK1_CPU1_R
J 0
(12850 3610);
DISPLAY 0.617021 (12850 3610);
PAINT ORANGE (12850 3610);
WIRE 16 -1 (12350 3450)(13700 3450);
FORCEPROP 2 LAST SIG_NAME SVID_CLK0_CPU1_R
J 0
(12850 3460);
DISPLAY 0.617021 (12850 3460);
PAINT ORANGE (12850 3460);
WIRE 16 -1 (11175 2250)(12175 2250);
FORCEPROP 2 LAST SIG_NAME PU_CPU1_SOCKET_ID_0
J 0
(11425 2260);
DISPLAY 0.617021 (11425 2260);
PAINT ORANGE (11425 2260);
WIRE 16 -1 (11175 2200)(12175 2200);
FORCEPROP 2 LAST SIG_NAME TP_CPU1_SOCKET_ID_2
J 0
(11425 2210);
DISPLAY 0.617021 (11425 2210);
PAINT ORANGE (11425 2210);
FORCEPROP 2 LASTPROP $XRERR UNIQUE?
J 0
(12205 2200);
DISPLAY 0.638298 (12205 2200);
PAINT MONO (12205 2200);
DISPLAY INVISIBLE (12205 2200);
WIRE 16 -1 (12850 2200)(12850 2050);
WIRE 16 -1 (13700 2050)(12850 2050);
WIRE 16 -1 (11175 2050)(12850 2050);
FORCEPROP 2 LAST SIG_NAME FM_CPU1_PROC_ID0
J 0
(11425 2060);
DISPLAY 0.617021 (11425 2060);
PAINT ORANGE (11425 2060);
WIRE 16 -1 (9275 1400)(8025 1400);
FORCEPROP 2 LAST SIG_NAME XDP_CPU_OBSFN_B0_MBP6_N
J 0
(8050 1410);
DISPLAY 0.617021 (8050 1410);
PAINT ORANGE (8050 1410);
WIRE 16 -1 (13100 1950)(11175 1950);
FORCEPROP 2 LAST SIG_NAME FM_CPU1_PKGID2
J 0
(11425 1960);
DISPLAY 0.617021 (11425 1960);
PAINT ORANGE (11425 1960);
WIRE 16 -1 (13700 1950)(13100 1950);
WIRE 16 -1 (13100 2200)(13100 1950);
WIRE 16 -1 (12600 2200)(12600 2100);
WIRE 16 -1 (13700 2100)(12600 2100);
WIRE 16 -1 (11175 2100)(12600 2100);
FORCEPROP 2 LAST SIG_NAME FM_CPU1_PROC_ID1
J 0
(11425 2110);
DISPLAY 0.617021 (11425 2110);
PAINT ORANGE (11425 2110);
WIRE 16 -1 (12150 3650)(11175 3650);
FORCEPROP 2 LAST SIG_NAME SVID_DIO1_CPU1
J 0
(11325 3660);
DISPLAY 0.617021 (11325 3660);
PAINT ORANGE (11325 3660);
FORCEPROP 2 LASTPROP $XRERR UNIQUE?
J 0
(11085 3660);
DISPLAY 0.638298 (11085 3660);
PAINT MONO (11085 3660);
DISPLAY INVISIBLE (11085 3660);
WIRE 16 -1 (12150 3600)(11175 3600);
FORCEPROP 2 LAST SIG_NAME SVID_CLK1_CPU1
J 0
(11325 3610);
DISPLAY 0.617021 (11325 3610);
PAINT ORANGE (11325 3610);
FORCEPROP 2 LASTPROP $XRERR UNIQUE?
J 0
(11085 3610);
DISPLAY 0.638298 (11085 3610);
PAINT MONO (11085 3610);
DISPLAY INVISIBLE (11085 3610);
WIRE 16 -1 (12150 3550)(11175 3550);
FORCEPROP 2 LAST SIG_NAME SVID_ALERT1_CPU1_N
J 0
(11325 3560);
DISPLAY 0.617021 (11325 3560);
PAINT ORANGE (11325 3560);
FORCEPROP 2 LASTPROP $XRERR UNIQUE?
J 0
(11085 3560);
DISPLAY 0.638298 (11085 3560);
PAINT MONO (11085 3560);
DISPLAY INVISIBLE (11085 3560);
WIRE 16 -1 (12150 3500)(11175 3500);
FORCEPROP 2 LAST SIG_NAME SVID_DIO0_CPU1
J 0
(11325 3510);
DISPLAY 0.617021 (11325 3510);
PAINT ORANGE (11325 3510);
FORCEPROP 2 LASTPROP $XRERR UNIQUE?
J 0
(11085 3510);
DISPLAY 0.638298 (11085 3510);
PAINT MONO (11085 3510);
DISPLAY INVISIBLE (11085 3510);
WIRE 16 -1 (12150 3450)(11175 3450);
FORCEPROP 2 LAST SIG_NAME SVID_CLK0_CPU1
J 0
(11325 3460);
DISPLAY 0.617021 (11325 3460);
PAINT ORANGE (11325 3460);
FORCEPROP 2 LASTPROP $XRERR UNIQUE?
J 0
(11085 3460);
DISPLAY 0.638298 (11085 3460);
PAINT MONO (11085 3460);
DISPLAY INVISIBLE (11085 3460);
WIRE 16 -1 (12150 3400)(11175 3400);
FORCEPROP 2 LAST SIG_NAME SVID_ALERT0_CPU1_N
J 0
(11325 3410);
DISPLAY 0.617021 (11325 3410);
PAINT ORANGE (11325 3410);
FORCEPROP 2 LASTPROP $XRERR UNIQUE?
J 0
(11085 3410);
DISPLAY 0.638298 (11085 3410);
PAINT MONO (11085 3410);
DISPLAY INVISIBLE (11085 3410);
WIRE 16 -1 (12725 3750)(11175 3750);
FORCEPROP 2 LAST SIG_NAME PECI_CPU_G
J 0
(11350 3760);
DISPLAY 0.617021 (11350 3760);
PAINT ORANGE (11350 3760);
WIRE 16 -1 (12750 4000)(11175 4000);
FORCEPROP 2 LAST SIG_NAME PD_CPU1_EAR_N
J 0
(11350 4010);
DISPLAY 0.617021 (11350 4010);
PAINT ORANGE (11350 4010);
WIRE 16 -1 (12000 3900)(11175 3900);
FORCEPROP 2 LAST SIG_NAME H_PM_SYNC_GTL_R2
J 0
(11350 3910);
DISPLAY 0.617021 (11350 3910);
PAINT ORANGE (11350 3910);
FORCEPROP 2 LASTPROP $XRERR UNIQUE?
J 0
(11110 3910);
DISPLAY 0.638298 (11110 3910);
PAINT MONO (11110 3910);
DISPLAY INVISIBLE (11110 3910);
WIRE 16 -1 (12000 3850)(11175 3850);
FORCEPROP 0 LAST SIG_NAME H_PMSYNC_CLK_24M_CPU1
J 0
(11340 3860);
DISPLAY 0.617021 (11340 3860);
PAINT ORANGE (11340 3860);
FORCEPROP 2 LASTPROP $XRERR UNIQUE?
J 0
(11100 3860);
DISPLAY 0.638298 (11100 3860);
PAINT MONO (11100 3860);
DISPLAY INVISIBLE (11100 3860);
WIRE 16 -1 (9275 3650)(8025 3650);
FORCEPROP 2 LAST SIG_NAME PWRGD_CPU1_DRAMPWROK_KLM_G
J 0
(8050 3660);
DISPLAY 0.617021 (8050 3660);
PAINT ORANGE (8050 3660);
WIRE 16 -1 (7475 2625)(7475 2700);
WIRE 16 -1 (9275 2700)(7475 2700);
FORCEPROP 2 LAST SIG_NAME A_CPU1_KLM_RCOMP1
J 0
(8050 2710);
DISPLAY 0.617021 (8050 2710);
PAINT ORANGE (8050 2710);
FORCEPROP 2 LASTPROP $XRERR UNIQUE?
J 0
(7810 2710);
DISPLAY 0.638298 (7810 2710);
PAINT MONO (7810 2710);
DISPLAY INVISIBLE (7810 2710);
WIRE 16 -1 (7700 2625)(7700 2650);
WIRE 16 -1 (9275 2650)(7700 2650);
FORCEPROP 2 LAST SIG_NAME A_CPU1_KLM_RCOMP0
J 0
(8050 2660);
DISPLAY 0.617021 (8050 2660);
PAINT ORANGE (8050 2660);
FORCEPROP 2 LASTPROP $XRERR UNIQUE?
J 0
(7810 2660);
DISPLAY 0.638298 (7810 2660);
PAINT MONO (7810 2660);
DISPLAY INVISIBLE (7810 2660);
WIRE 16 -1 (9275 1950)(9025 1950);
WIRE 16 -1 (9025 1950)(9025 2000);
WIRE 16 -1 (9025 2000)(9275 2000);
WIRE 16 -1 (6600 2000)(6600 1525);
WIRE 16 -1 (6600 2000)(9025 2000);
FORCEPROP 2 LAST SIG_NAME A_CPU1_PE3_RBIAS
J 0
(8050 2010);
DISPLAY 0.617021 (8050 2010);
PAINT ORANGE (8050 2010);
FORCEPROP 2 LASTPROP $XRERR UNIQUE?
J 0
(7810 2010);
DISPLAY 0.638298 (7810 2010);
PAINT MONO (7810 2010);
DISPLAY INVISIBLE (7810 2010);
WIRE 16 -1 (9275 1850)(9025 1850);
WIRE 16 -1 (6825 1900)(6825 1525);
WIRE 16 -1 (9025 1900)(6825 1900);
FORCEPROP 2 LAST SIG_NAME A_CPU1_PE012_RBIAS
J 0
(8050 1910);
DISPLAY 0.617021 (8050 1910);
PAINT ORANGE (8050 1910);
FORCEPROP 2 LASTPROP $XRERR UNIQUE?
J 0
(7810 1910);
DISPLAY 0.638298 (7810 1910);
PAINT MONO (7810 1910);
DISPLAY INVISIBLE (7810 1910);
WIRE 16 -1 (9025 1850)(9025 1900);
WIRE 16 -1 (9275 1900)(9025 1900);
WIRE 16 -1 (9025 1750)(9275 1750);
WIRE 16 -1 (9025 1800)(9025 1750);
WIRE 16 -1 (9025 1800)(9275 1800);
WIRE 16 -1 (7050 1800)(9025 1800);
FORCEPROP 2 LAST SIG_NAME A_CPU1_UPI01_RBIAS
J 0
(8050 1810);
DISPLAY 0.617021 (8050 1810);
PAINT ORANGE (8050 1810);
FORCEPROP 2 LASTPROP $XRERR UNIQUE?
J 0
(7810 1810);
DISPLAY 0.638298 (7810 1810);
PAINT MONO (7810 1810);
DISPLAY INVISIBLE (7810 1810);
WIRE 16 -1 (7050 1525)(7050 1800);
WIRE 16 -1 (9025 1650)(9275 1650);
WIRE 16 -1 (9025 1700)(9025 1650);
WIRE 16 -1 (9025 1700)(9275 1700);
WIRE 16 -1 (7275 1700)(9025 1700);
FORCEPROP 2 LAST SIG_NAME A_CPU1_UPI2_RBIAS
J 0
(8050 1710);
DISPLAY 0.617021 (8050 1710);
PAINT ORANGE (8050 1710);
FORCEPROP 2 LASTPROP $XRERR UNIQUE?
J 0
(7810 1710);
DISPLAY 0.638298 (7810 1710);
PAINT MONO (7810 1710);
DISPLAY INVISIBLE (7810 1710);
WIRE 16 -1 (7275 1525)(7275 1700);
WIRE 16 -1 (8025 1250)(9275 1250);
FORCEPROP 2 LAST SIG_NAME TP_XDP_CPU1_OBSDATA_B1_MBP3_N
J 0
(8040 1260);
DISPLAY 0.617021 (8040 1260);
PAINT ORANGE (8040 1260);
FORCEPROP 2 LASTPROP $XRERR UNIQUE?
J 0
(7785 1250);
DISPLAY 0.638298 (7785 1250);
PAINT MONO (7785 1250);
DISPLAY INVISIBLE (7785 1250);
WIRE 16 -1 (8025 1450)(9275 1450);
FORCEPROP 2 LAST SIG_NAME XDP_CPU_OBSFN_B1_MBP7_N
J 0
(8050 1460);
DISPLAY 0.617021 (8050 1460);
PAINT ORANGE (8050 1460);
WIRE 16 -1 (8025 950)(9275 950);
FORCEPROP 2 LAST SIG_NAME XDP_CPU_TCK0
J 0
(8050 960);
DISPLAY 0.617021 (8050 960);
PAINT ORANGE (8050 960);
WIRE 16 -1 (8025 1000)(9275 1000);
FORCEPROP 2 LAST SIG_NAME XDP_CPU1_TDI
J 0
(8050 1010);
DISPLAY 0.617021 (8050 1010);
PAINT ORANGE (8050 1010);
WIRE 16 -1 (8025 1100)(9275 1100);
FORCEPROP 2 LAST SIG_NAME XDP_CPU_MBP0_N
J 0
(8050 1110);
DISPLAY 0.617021 (8050 1110);
PAINT ORANGE (8050 1110);
WIRE 16 -1 (8025 1150)(9275 1150);
FORCEPROP 2 LAST SIG_NAME XDP_CPU_MBP1_N
J 0
(8050 1160);
DISPLAY 0.617021 (8050 1160);
PAINT ORANGE (8050 1160);
WIRE 16 -1 (8025 1200)(9275 1200);
FORCEPROP 2 LAST SIG_NAME TP_XDP_CPU1_OBSDATA_B0_MBP2_N
J 0
(8040 1210);
DISPLAY 0.617021 (8040 1210);
PAINT ORANGE (8040 1210);
FORCEPROP 2 LASTPROP $XRERR UNIQUE?
J 0
(7785 1200);
DISPLAY 0.638298 (7785 1200);
PAINT MONO (7785 1200);
DISPLAY INVISIBLE (7785 1200);
WIRE 16 -1 (8275 2500)(9275 2500);
FORCEPROP 2 LAST SIG_NAME SMB_DDR_GHJ_SDA_G_R
J 0
(8300 2510);
DISPLAY 0.617021 (8300 2510);
PAINT ORANGE (8300 2510);
WIRE 16 -1 (7250 2625)(7250 2750);
WIRE 16 -1 (9275 2750)(7250 2750);
FORCEPROP 2 LAST SIG_NAME A_CPU1_KLM_RCOMP2
J 0
(8050 2760);
DISPLAY 0.617021 (8050 2760);
PAINT ORANGE (8050 2760);
FORCEPROP 2 LASTPROP $XRERR UNIQUE?
J 0
(7810 2760);
DISPLAY 0.638298 (7810 2760);
PAINT MONO (7810 2760);
DISPLAY INVISIBLE (7810 2760);
WIRE 16 -1 (6800 2750)(6800 2850);
WIRE 16 -1 (9275 2850)(6800 2850);
FORCEPROP 2 LAST SIG_NAME A_CPU1_GHJ_RCOMP1
J 0
(8050 2860);
DISPLAY 0.617021 (8050 2860);
PAINT ORANGE (8050 2860);
FORCEPROP 2 LASTPROP $XRERR UNIQUE?
J 0
(7810 2860);
DISPLAY 0.638298 (7810 2860);
PAINT MONO (7810 2860);
DISPLAY INVISIBLE (7810 2860);
WIRE 16 -1 (9275 3550)(8000 3550);
FORCEPROP 2 LAST SIG_NAME M_GHJ_RST_N
J 0
(8025 3560);
DISPLAY 0.617021 (8025 3560);
PAINT ORANGE (8025 3560);
WIRE 16 -1 (9275 3700)(8025 3700);
FORCEPROP 2 LAST SIG_NAME PWRGD_CPU1_DRAMPWROK_GHJ_G
J 0
(8050 3710);
DISPLAY 0.617021 (8050 3710);
PAINT ORANGE (8050 3710);
WIRE 16 -1 (9275 4000)(8025 4000);
FORCEPROP 2 LAST SIG_NAME CLK_100M_CPU1_BCLK1_DP
J 0
(8050 4010);
DISPLAY 0.617021 (8050 4010);
PAINT ORANGE (8050 4010);
WIRE 16 -1 (9275 4100)(8025 4100);
FORCEPROP 2 LAST SIG_NAME CLK_100M_CPU1_BCLK0_DN
J 0
(8050 4110);
DISPLAY 0.617021 (8050 4110);
PAINT ORANGE (8050 4110);
WIRE 16 -1 (9275 4150)(8025 4150);
FORCEPROP 2 LAST SIG_NAME CLK_100M_CPU1_BCLK0_DP
J 0
(8050 4160);
DISPLAY 0.617021 (8050 4160);
PAINT ORANGE (8050 4160);
WIRE 16 -1 (12175 3150)(11175 3150);
FORCEPROP 2 LAST SIG_NAME H_CPU1_ERR1_G_N
J 0
(11425 3160);
DISPLAY 0.617021 (11425 3160);
PAINT ORANGE (11425 3160);
WIRE 16 -1 (12750 4150)(11175 4150);
FORCEPROP 2 LAST SIG_NAME PWRGD_CPU1_G
J 0
(11350 4160);
DISPLAY 0.617021 (11350 4160);
PAINT ORANGE (11350 4160);
WIRE 16 -1 (12475 1750)(11175 1750);
FORCEPROP 2 LAST SIG_NAME PU_CPU1_TSC_SYNC
J 0
(11438 1772);
DISPLAY 0.617021 (11438 1772);
PAINT ORANGE (11438 1772);
WIRE 16 -1 (12475 1200)(11175 1200);
FORCEPROP 2 LAST SIG_NAME PD_CPU1_TEST13
J 0
(11425 1210);
DISPLAY 0.617021 (11425 1210);
PAINT ORANGE (11425 1210);
WIRE 16 -1 (12475 1250)(11175 1250);
FORCEPROP 2 LAST SIG_NAME PD_CPU1_TEST14
J 0
(11425 1260);
DISPLAY 0.617021 (11425 1260);
PAINT ORANGE (11425 1260);
WIRE 16 -1 (9275 1350)(8025 1350);
FORCEPROP 2 LAST SIG_NAME TP_XDP_CPU1_OBSDATA_B3_MBP5_N
J 0
(8040 1360);
DISPLAY 0.617021 (8040 1360);
PAINT ORANGE (8040 1360);
FORCEPROP 2 LASTPROP $XRERR UNIQUE?
J 0
(7785 1350);
DISPLAY 0.638298 (7785 1350);
PAINT MONO (7785 1350);
DISPLAY INVISIBLE (7785 1350);
WIRE 16 -1 (9275 1300)(8025 1300);
FORCEPROP 2 LAST SIG_NAME TP_XDP_CPU1_OBSDATA_B2_MBP4_N
J 0
(8040 1310);
DISPLAY 0.617021 (8040 1310);
PAINT ORANGE (8040 1310);
FORCEPROP 2 LASTPROP $XRERR UNIQUE?
J 0
(7785 1300);
DISPLAY 0.638298 (7785 1300);
PAINT MONO (7785 1300);
DISPLAY INVISIBLE (7785 1300);
WIRE 16 -1 (9025 1550)(9275 1550);
WIRE 16 -1 (9025 1600)(9025 1550);
WIRE 16 -1 (9025 1600)(9275 1600);
WIRE 16 -1 (7500 1600)(9025 1600);
FORCEPROP 2 LAST SIG_NAME A_CPU1_MCP01_RBIAS
J 0
(8050 1610);
DISPLAY 0.617021 (8050 1610);
PAINT ORANGE (8050 1610);
FORCEPROP 2 LASTPROP $XRERR UNIQUE?
J 0
(7810 1610);
DISPLAY 0.638298 (7810 1610);
PAINT MONO (7810 1610);
DISPLAY INVISIBLE (7810 1610);
WIRE 16 -1 (7500 1525)(7500 1600);
WIRE 16 -1 (12750 3900)(12200 3900);
FORCEPROP 2 LAST SIG_NAME H_PM_SYNC_GTL
J 0
(12240 3910);
DISPLAY 0.617021 (12240 3910);
PAINT ORANGE (12240 3910);
WIRE 16 -1 (12175 3100)(11175 3100);
FORCEPROP 2 LAST SIG_NAME H_CPU1_ERR0_G_N
J 0
(11425 3110);
DISPLAY 0.617021 (11425 3110);
PAINT ORANGE (11425 3110);
WIRE 16 -1 (12175 3200)(11175 3200);
FORCEPROP 2 LAST SIG_NAME H_CPU1_ERR2_G_N
J 0
(11425 3210);
DISPLAY 0.617021 (11425 3210);
PAINT ORANGE (11425 3210);
WIRE 16 -1 (12750 4100)(11175 4100);
FORCEPROP 2 LAST SIG_NAME RST_CPU1_G_N
J 0
(11350 4110);
DISPLAY 0.617021 (11350 4110);
PAINT ORANGE (11350 4110);
WIRE 16 -1 (13350 625)(13350 200);
WIRE 16 -1 (12900 625)(12900 200);
WIRE 16 -1 (11675 650)(13925 650);
WIRE 16 -1 (13925 175)(13925 650);
WIRE 16 -1 (11675 650)(11675 175);
WIRE 16 -1 (11675 175)(13925 175);
WIRE 16 -1 (11725 525)(13875 525);
WIRE 16 -1 (11725 450)(13875 450);
WIRE 16 -1 (11725 325)(13850 325);
WIRE 16 -1 (11725 250)(13875 250);
WIRE 16 -1 (12125 625)(12125 200);
WIRE 16 -1 (9275 2100)(8050 2100);
FORCEPROP 2 LAST SIG_NAME SMB_PIROM_CPU1_SDA
J 0
(8075 2110);
DISPLAY 0.617021 (8075 2110);
PAINT ORANGE (8075 2110);
WIRE 16 -1 (9275 2150)(8050 2150);
FORCEPROP 2 LAST SIG_NAME SMB_PIROM_CPU1_SCL
J 0
(8075 2160);
DISPLAY 0.617021 (8075 2160);
PAINT ORANGE (8075 2160);
WIRE 16 -1 (9275 3000)(8000 3000);
FORCEPROP 2 LAST SIG_NAME M_G_CPU_VREF
J 0
(8025 3010);
DISPLAY 0.617021 (8025 3010);
PAINT ORANGE (8025 3010);
WIRE 16 -1 (9275 3100)(8000 3100);
FORCEPROP 2 LAST SIG_NAME M_J_CPU_VREF
J 0
(8025 3110);
DISPLAY 0.617021 (8025 3110);
PAINT ORANGE (8025 3110);
WIRE 16 -1 (8000 3150)(9275 3150);
FORCEPROP 2 LAST SIG_NAME M_K_CPU_VREF
J 0
(8025 3160);
DISPLAY 0.617021 (8025 3160);
PAINT ORANGE (8025 3160);
WIRE 16 -1 (9275 900)(8025 900);
FORCEPROP 2 LAST SIG_NAME XDP_CPU_TMS
J 0
(8050 910);
DISPLAY 0.617021 (8050 910);
PAINT ORANGE (8050 910);
WIRE 16 -1 (8025 850)(9275 850);
FORCEPROP 2 LAST SIG_NAME XDP_CPU_TRST_N
J 0
(8050 860);
DISPLAY 0.617021 (8050 860);
PAINT ORANGE (8050 860);
WIRE 16 -1 (9275 3850)(8025 3850);
FORCEPROP 2 LAST SIG_NAME CLK_100M_CPU1_BCLK2_DP
J 0
(8050 3860);
DISPLAY 0.617021 (8050 3860);
PAINT ORANGE (8050 3860);
WIRE 16 -1 (9275 3500)(8000 3500);
FORCEPROP 2 LAST SIG_NAME M_KLM_RST_N
J 0
(8025 3510);
DISPLAY 0.617021 (8025 3510);
PAINT ORANGE (8025 3510);
WIRE 16 -1 (8025 3350)(9275 3350);
FORCEPROP 2 LAST SIG_NAME H_CPU1_MEMKLM_MEMHOT_G_N
J 0
(8050 3360);
DISPLAY 0.617021 (8050 3360);
PAINT ORANGE (8050 3360);
WIRE 16 -1 (9275 2450)(8275 2450);
FORCEPROP 2 LAST SIG_NAME SMB_DDR_KLM_SCL_G_R
J 0
(8300 2460);
DISPLAY 0.617021 (8300 2460);
PAINT ORANGE (8300 2460);
WIRE 16 -1 (9275 2550)(8275 2550);
FORCEPROP 2 LAST SIG_NAME SMB_DDR_KLM_SDA_G_R
J 0
(8300 2560);
DISPLAY 0.617021 (8300 2560);
PAINT ORANGE (8300 2560);
WIRE 16 -1 (8300 2250)(9275 2250);
FORCEPROP 2 LAST SIG_NAME SMB_CPU1_PE_HP_GTL_SDA
J 0
(8300 2260);
DISPLAY 0.617021 (8300 2260);
PAINT ORANGE (8300 2260);
WIRE 16 -1 (8275 2400)(9275 2400);
FORCEPROP 2 LAST SIG_NAME SMB_DDR_GHJ_SCL_G_R
J 0
(8300 2410);
DISPLAY 0.617021 (8300 2410);
PAINT ORANGE (8300 2410);
WIRE 16 -1 (9275 2300)(8275 2300);
FORCEPROP 2 LAST SIG_NAME SMB_CPU1_PE_HP_GTL_SCL
J 0
(8300 2310);
DISPLAY 0.617021 (8300 2310);
PAINT ORANGE (8300 2310);
WIRE 16 -1 (12175 2550)(11175 2550);
FORCEPROP 2 LAST SIG_NAME PU_CPU1_TXT_AGENT
J 0
(11425 2560);
DISPLAY 0.617021 (11425 2560);
PAINT ORANGE (11425 2560);
WIRE 16 -1 (12175 2600)(11175 2600);
FORCEPROP 2 LAST SIG_NAME H_CPU1_BMCINIT
J 0
(11425 2610);
DISPLAY 0.617021 (11425 2610);
PAINT ORANGE (11425 2610);
WIRE 16 -1 (12175 2800)(11175 2800);
FORCEPROP 2 LAST SIG_NAME H_CPU1_THERMTRIP_G_N
J 0
(11425 2810);
DISPLAY 0.617021 (11425 2810);
PAINT ORANGE (11425 2810);
WIRE 16 -1 (12175 2650)(11175 2650);
FORCEPROP 2 LAST SIG_NAME PU_CPU1_FRMAGENT
J 0
(11425 2660);
DISPLAY 0.617021 (11425 2660);
PAINT ORANGE (11425 2660);
WIRE 16 -1 (12175 2700)(11175 2700);
FORCEPROP 2 LAST SIG_NAME PU_CPU1_SAFE_MODE_BOOT
J 0
(11425 2710);
DISPLAY 0.617021 (11425 2710);
PAINT ORANGE (11425 2710);
WIRE 16 -1 (12150 2850)(11175 2850);
FORCEPROP 2 LAST SIG_NAME H_CPU1_PROCHOT_G_N
J 0
(11425 2860);
DISPLAY 0.617021 (11425 2860);
PAINT ORANGE (11425 2860);
WIRE 16 -1 (12150 3000)(11175 3000);
FORCEPROP 2 LAST SIG_NAME H_CPU1_MSMI_G_N
J 0
(11425 3010);
DISPLAY 0.617021 (11425 3010);
PAINT ORANGE (11425 3010);
WIRE 16 -1 (12475 1150)(11175 1150);
FORCEPROP 2 LAST SIG_NAME PD_CPU1_TEST12
J 0
(11425 1160);
DISPLAY 0.617021 (11425 1160);
PAINT ORANGE (11425 1160);
WIRE 16 -1 (12475 1550)(11175 1550);
FORCEPROP 2 LAST SIG_NAME PU_CPU1_LEGACY_SKT
J 0
(11425 1560);
DISPLAY 0.617021 (11425 1560);
PAINT ORANGE (11425 1560);
WIRE 16 -1 (12475 1600)(11175 1600);
FORCEPROP 2 LAST SIG_NAME TP_CPU1_NMI
J 0
(11425 1610);
DISPLAY 0.617021 (11425 1610);
PAINT ORANGE (11425 1610);
FORCEPROP 2 LASTPROP $XRERR UNIQUE?
J 0
(12505 1600);
DISPLAY 0.638298 (12505 1600);
PAINT MONO (12505 1600);
DISPLAY INVISIBLE (12505 1600);
WIRE 16 -1 (12475 1700)(11175 1700);
FORCEPROP 2 LAST SIG_NAME FM_CPU1_SM_WP
J 0
(11425 1710);
DISPLAY 0.617021 (11425 1710);
PAINT ORANGE (11425 1710);
WIRE 16 -1 (12750 3850)(12200 3850);
FORCEPROP 2 LAST SIG_NAME H_PMSYNC_CLK_24M
J 0
(12240 3860);
DISPLAY 0.617021 (12240 3860);
PAINT ORANGE (12240 3860);
WIRE 16 -1 (12475 1300)(11175 1300);
FORCEPROP 2 LAST SIG_NAME PD_CPU1_KSFC_DIS
J 0
(11427 1306);
DISPLAY 0.617021 (11427 1306);
PAINT ORANGE (11427 1306);
WIRE 16 -1 (12500 1050)(11175 1050);
FORCEPROP 2 LAST SIG_NAME XDP_CPU_PREQ_N
J 0
(11425 1060);
DISPLAY 0.617021 (11425 1060);
PAINT ORANGE (11425 1060);
WIRE 16 -1 (12500 1000)(11175 1000);
FORCEPROP 2 LAST SIG_NAME XDP_CPU_PRDY_N
J 0
(11425 1010);
DISPLAY 0.617021 (11425 1010);
PAINT ORANGE (11425 1010);
WIRE 16 -1 (12475 1450)(11175 1450);
FORCEPROP 2 LAST SIG_NAME PD_PIROM_CPU1_ADDR2
J 0
(11425 1460);
DISPLAY 0.617021 (11425 1460);
PAINT ORANGE (11425 1460);
WIRE 16 -1 (12475 1400)(11175 1400);
FORCEPROP 2 LAST SIG_NAME PD_PIROM_CPU1_ADDR1
J 0
(11425 1410);
DISPLAY 0.617021 (11425 1410);
PAINT ORANGE (11425 1410);
WIRE 16 -1 (12475 1350)(11175 1350);
FORCEPROP 2 LAST SIG_NAME PU_PIROM_CPU1_ADDR0
J 0
(11425 1360);
DISPLAY 0.617021 (11425 1360);
PAINT ORANGE (11425 1360);
WIRE 16 -1 (12525 800)(11175 800);
FORCEPROP 2 LAST SIG_NAME XDP_CPU1_TDO
J 0
(11425 810);
DISPLAY 0.617021 (11425 810);
PAINT ORANGE (11425 810);
WIRE 16 -1 (13275 1000)(13275 900);
WIRE 16 -1 (13275 900)(13525 900);
WIRE 16 -1 (11175 900)(13275 900);
FORCEPROP 2 LAST SIG_NAME FM_CPU1_SKTOCC_LVT3_N
J 0
(11425 910);
DISPLAY 0.617021 (11425 910);
PAINT ORANGE (11425 910);
WIRE 16 -1 (11175 2300)(12175 2300);
FORCEPROP 2 LAST SIG_NAME PU_CPU1_SOCKET_ID_1
J 0
(11425 2310);
DISPLAY 0.617021 (11425 2310);
PAINT ORANGE (11425 2310);
WIRE 16 -1 (12150 2400)(11175 2400);
FORCEPROP 2 LAST SIG_NAME H_CPU1_FAST_WAKE_N
J 0
(11425 2410);
DISPLAY 0.617021 (11425 2410);
PAINT ORANGE (11425 2410);
WIRE 16 -1 (12175 2450)(11175 2450);
FORCEPROP 2 LAST SIG_NAME PD_CPU1_BIST_ENABLE
J 0
(11425 2460);
DISPLAY 0.617021 (11425 2460);
PAINT ORANGE (11425 2460);
WIRE 16 -1 (12175 2500)(11175 2500);
FORCEPROP 2 LAST SIG_NAME PD_CPU1_TXT_PLTEN
J 0
(11425 2510);
DISPLAY 0.617021 (11425 2510);
PAINT ORANGE (11425 2510);
DOT 1 (6600 1200);
DOT 1 (6825 1200);
DOT 1 (7050 1200);
DOT 1 (7275 1200);
DOT 1 (6650 2350);
DOT 1 (6800 2350);
DOT 1 (7025 2350);
DOT 1 (9025 1600);
DOT 1 (9025 1800);
DOT 1 (9025 1900);
DOT 1 (9025 2000);
DOT 1 (13275 900);
DOT 1 (13100 1950);
DOT 1 (13350 1900);
DOT 1 (13600 1850);
DOT 1 (12850 2050);
DOT 1 (12600 2100);
DOT 1 (12850 2500);
DOT 1 (13100 2500);
DOT 1 (13325 3650);
DOT 1 (13350 2500);
DOT 1 (13600 2500);
DOT 1 (13325 4175);
DOT 1 (7475 2350);
DOT 1 (9025 1700);
DOT 1 (7250 2350);
DOT 1 (13600 3550);
DOT 1 (13325 3500);
DOT 1 (13600 3400);
DOT 1 (13600 2875);
FORCENOTE
HOST FABRIC INTERFACE
(13375 400) 0;
DISPLAY LEFT (13375 400);
DISPLAY 0.638298 (13375 400);
PAINT PURPLE (13375 400);
FORCENOTE
DEFINITION
(13500 575) 0;
DISPLAY LEFT (13500 575);
DISPLAY 0.808511 (13500 575);
PAINT PURPLE (13500 575);
FORCENOTE
NON-MCP SUPPORT
(13375 475) 0;
DISPLAY LEFT (13375 475);
DISPLAY 0.638298 (13375 475);
PAINT PURPLE (13375 475);
FORCENOTE
MCP SUPPORT
(13375 350) 0;
DISPLAY LEFT (13375 350);
DISPLAY 0.638298 (13375 350);
PAINT PURPLE (13375 350);
FORCENOTE
RESERVED
(13400 200) 0;
DISPLAY LEFT (13400 200);
DISPLAY 0.638298 (13400 200);
PAINT PURPLE (13400 200);
FORCENOTE
RESERVED
(13400 275) 0;
DISPLAY LEFT (13400 275);
DISPLAY 0.638298 (13400 275);
PAINT PURPLE (13400 275);
FORCENOTE
PKG_ID[2:0]
(12925 575) 0;
DISPLAY LEFT (12925 575);
DISPLAY 0.808511 (12925 575);
PAINT PURPLE (12925 575);
FORCENOTE
3'B111-3'B011
(12950 200) 0;
DISPLAY LEFT (12950 200);
DISPLAY 0.638298 (12950 200);
PAINT PURPLE (12950 200);
FORCENOTE
3'B000
(12950 475) 0;
DISPLAY LEFT (12950 475);
DISPLAY 0.638298 (12950 475);
PAINT PURPLE (12950 475);
FORCENOTE
3'B010
(12950 275) 0;
DISPLAY LEFT (12950 275);
DISPLAY 0.638298 (12950 275);
PAINT PURPLE (12950 275);
FORCENOTE
3'B001
(12950 375) 0;
DISPLAY LEFT (12950 375);
DISPLAY 0.638298 (12950 375);
PAINT PURPLE (12950 375);
FORCENOTE
DEFINITION
(12325 575) 0;
DISPLAY LEFT (12325 575);
DISPLAY 0.808511 (12325 575);
PAINT PURPLE (12325 575);
FORCENOTE
RESERVED FOR FUTURE PROCESSOR
(12150 375) 0;
DISPLAY LEFT (12150 375);
DISPLAY 0.638298 (12150 375);
PAINT PURPLE (12150 375);
FORCENOTE
SKYLAKE PROCESSOR 
(12150 475) 0;
DISPLAY LEFT (12150 475);
DISPLAY 0.638298 (12150 475);
PAINT PURPLE (12150 475);
FORCENOTE
RESERVED
(12150 200) 0;
DISPLAY LEFT (12150 200);
DISPLAY 0.638298 (12150 200);
PAINT PURPLE (12150 200);
FORCENOTE
RESERVED
(12150 275) 0;
DISPLAY LEFT (12150 275);
DISPLAY 0.638298 (12150 275);
PAINT PURPLE (12150 275);
FORCENOTE
2'B11
(11825 200) 0;
DISPLAY LEFT (11825 200);
DISPLAY 0.638298 (11825 200);
PAINT PURPLE (11825 200);
FORCENOTE
2'B00
(11825 475) 0;
DISPLAY LEFT (11825 475);
DISPLAY 0.638298 (11825 475);
PAINT PURPLE (11825 475);
FORCENOTE
2'B10
(11825 275) 0;
DISPLAY LEFT (11825 275);
DISPLAY 0.638298 (11825 275);
PAINT PURPLE (11825 275);
FORCENOTE
2'B01
(11825 375) 0;
DISPLAY LEFT (11825 375);
DISPLAY 0.638298 (11825 375);
PAINT PURPLE (11825 375);
FORCENOTE
PROC_ID [1:0]
(11725 575) 0;
DISPLAY LEFT (11725 575);
DISPLAY 0.808511 (11725 575);
PAINT PURPLE (11725 575);
FORCENOTE
PIROM_ADDR[2:0] 3B001
(13092 1492) 0;
DISPLAY LEFT (13092 1492);
DISPLAY 1.021277 (13092 1492);
PAINT PURPLE (13092 1492);
FORCENOTE
ALTERNATE: H63715-002
(6525 4275) 0;
DISPLAY LEFT (6525 4275);
DISPLAY 0.808511 (6525 4275);
PAINT PURPLE (6525 4275);
QUIT
